G04 ================== begin FILE IDENTIFICATION RECORD ==================*
G04 Layout Name:  D:/<user>/Wistron_project/16318-2/gbr/16318-2.brd*
G04 Film Name:    TMASK*
G04 File Format:  Gerber RS274X*
G04 File Origin:  Cadence Allegro 16.5-S056*
G04 Origin Date:  Mon Aug 07 11:09:24 2017*
G04 *
G04 Layer:  VIA CLASS/SOLDERMASK_TOP*
G04 Layer:  PIN/SOLDERMASK_TOP*
G04 Layer:  PACKAGE GEOMETRY/SOLDERMASK_TOP*
G04 Layer:  DRAWING FORMAT/LAYER_PCB_STORY*
G04 Layer:  DRAWING FORMAT/LAYER_SOLDER_T*
G04 Layer:  BOARD GEOMETRY/SOLDERMASK_TOP*
G04 *
G04 Offset:    (0.00 0.00)*
G04 Mirror:    No*
G04 Mode:      Positive*
G04 Rotation:  0*
G04 FullContactRelief:  No*
G04 UndefLineWidth:     6.00*
G04 ================== end FILE IDENTIFICATION RECORD ====================*
%FSLAX35Y35*MOIN*%
%IR0*IPPOS*OFA0.00000B0.00000*MIA0B0*SFA1.00000B1.00000*%
%AMMACRO56*
4,1,40,.013,.017,
-.013,.017,
-.013695,.016939,
-.014368,.016759,
-.015,.016464,
-.015571,.016064,
-.016064,.015571,
-.016464,.015,
-.016759,.014368,
-.016939,.013695,
-.017,.013,
-.017,-.013,
-.016939,-.013695,
-.016759,-.014368,
-.016464,-.015,
-.016064,-.015571,
-.015571,-.016064,
-.015,-.016464,
-.014368,-.016759,
-.013695,-.016939,
-.013,-.017,
.013,-.017,
.013695,-.016939,
.014368,-.016759,
.015,-.016464,
.015571,-.016064,
.016064,-.015571,
.016464,-.015,
.016759,-.014368,
.016939,-.013695,
.017,-.013,
.017,.013,
.016939,.013695,
.016759,.014368,
.016464,.015,
.016064,.015571,
.015571,.016064,
.015,.016464,
.014368,.016759,
.013695,.016939,
.013,.017,
0.0*
%
%ADD56MACRO56*%
%AMMACRO17*
4,1,40,.017,-.013,
.017,.013,
.016939,.013695,
.016759,.014368,
.016464,.015,
.016064,.015571,
.015571,.016064,
.015,.016464,
.014368,.016759,
.013695,.016939,
.013,.017,
-.013,.017,
-.013695,.016939,
-.014368,.016759,
-.015,.016464,
-.015571,.016064,
-.016064,.015571,
-.016464,.015,
-.016759,.014368,
-.016939,.013695,
-.017,.013,
-.017,-.013,
-.016939,-.013695,
-.016759,-.014368,
-.016464,-.015,
-.016064,-.015571,
-.015571,-.016064,
-.015,-.016464,
-.014368,-.016759,
-.013695,-.016939,
-.013,-.017,
.013,-.017,
.013695,-.016939,
.014368,-.016759,
.015,-.016464,
.015571,-.016064,
.016064,-.015571,
.016464,-.015,
.016759,-.014368,
.016939,-.013695,
.017,-.013,
0.0*
%
%ADD17MACRO17*%
%AMMACRO85*
4,1,40,.008,.009,
.008695,.008939,
.009368,.008759,
.01,.008464,
.010571,.008064,
.011064,.007571,
.011464,.007,
.011759,.006368,
.011939,.005695,
.012,.005,
.012,-.005,
.011939,-.005695,
.011759,-.006368,
.011464,-.007,
.011064,-.007571,
.010571,-.008064,
.01,-.008464,
.009368,-.008759,
.008695,-.008939,
.008,-.009,
-.008,-.009,
-.008695,-.008939,
-.009368,-.008759,
-.01,-.008464,
-.010571,-.008064,
-.011064,-.007571,
-.011464,-.007,
-.011759,-.006368,
-.011939,-.005695,
-.012,-.005,
-.012,.005,
-.011939,.005695,
-.011759,.006368,
-.011464,.007,
-.011064,.007571,
-.010571,.008064,
-.01,.008464,
-.009368,.008759,
-.008695,.008939,
-.008,.009,
.008,.009,
0.0*
%
%ADD85MACRO85*%
%ADD70O,.06X.111*%
%AMMACRO66*
4,1,15,-.0275,-.115,
-.0275,.02323,
-.02431,.026923,
-.021809,.031114,
-.020074,.035675,
-.019157,.040469,
-.019087,.045348,
-.019865,.050166,
-.021468,.054776,
-.023847,.059037,
-.02693,.06282,
-.0275,.06339,
-.0275,.115,
.0275,.115,
.0275,-.115,
-.0275,-.115,
0.0*
%
%ADD66MACRO66*%
%ADD139R,.143X.011*%
%ADD136R,.01X.007*%
%ADD122R,.007X.01*%
%ADD10C,.02*%
%ADD106C,.03*%
%ADD39C,.022*%
%AMMACRO143*
4,1,40,-.007,.004,
-.007,-.004,
-.00697,-.004347,
-.006879,-.004684,
-.006732,-.005,
-.006532,-.005286,
-.006286,-.005532,
-.006,-.005732,
-.005684,-.005879,
-.005347,-.00597,
-.005,-.006,
.005,-.006,
.005347,-.00597,
.005684,-.005879,
.006,-.005732,
.006286,-.005532,
.006532,-.005286,
.006732,-.005,
.006879,-.004684,
.00697,-.004347,
.007,-.004,
.007,.004,
.00697,.004347,
.006879,.004684,
.006732,.005,
.006532,.005286,
.006286,.005532,
.006,.005732,
.005684,.005879,
.005347,.00597,
.005,.006,
-.005,.006,
-.005347,.00597,
-.005684,.005879,
-.006,.005732,
-.006286,.005532,
-.006532,.005286,
-.006732,.005,
-.006879,.004684,
-.00697,.004347,
-.007,.004,
0.0*
%
%ADD143MACRO143*%
%ADD113C,.05*%
%ADD58C,.032*%
%ADD27C,.014*%
%ADD80C,.042*%
%ADD74C,.034*%
%ADD51C,.016*%
%ADD46C,.08*%
%ADD28C,.026*%
%ADD118C,.036*%
%ADD45C,.028*%
%ADD117C,.029*%
%ADD11C,.056*%
%ADD73C,.048*%
%ADD111C,.094*%
%ADD18C,.086*%
%ADD137R,.128X.098*%
%ADD126R,.062X.062*%
%AMMACRO64*
4,1,40,.0225,-.007,
.022378,-.008389,
.022018,-.009736,
.021428,-.011,
.020628,-.012142,
.019642,-.013128,
.0185,-.013928,
.017236,-.014518,
.015889,-.014878,
.0145,-.015,
-.0145,-.015,
-.015889,-.014878,
-.017236,-.014518,
-.0185,-.013928,
-.019642,-.013128,
-.020628,-.012142,
-.021428,-.011,
-.022018,-.009736,
-.022378,-.008389,
-.0225,-.007,
-.0225,.007,
-.022378,.008389,
-.022018,.009736,
-.021428,.011,
-.020628,.012142,
-.019642,.013128,
-.0185,.013928,
-.017236,.014518,
-.015889,.014878,
-.0145,.015,
.0145,.015,
.015889,.014878,
.017236,.014518,
.0185,.013928,
.019642,.013128,
.020628,.012142,
.021428,.011,
.022018,.009736,
.022378,.008389,
.0225,.007,
.0225,-.007,
0.0*
%
%ADD64MACRO64*%
%ADD110C,.097*%
%AMMACRO78*
4,1,40,-.007,-.0225,
-.008389,-.022378,
-.009736,-.022018,
-.011,-.021428,
-.012142,-.020628,
-.013128,-.019642,
-.013928,-.0185,
-.014518,-.017236,
-.014878,-.015889,
-.015,-.0145,
-.015,.0145,
-.014878,.015889,
-.014518,.017236,
-.013928,.0185,
-.013128,.019642,
-.012142,.020628,
-.011,.021428,
-.009736,.022018,
-.008389,.022378,
-.007,.0225,
.007,.0225,
.008389,.022378,
.009736,.022018,
.011,.021428,
.012142,.020628,
.013128,.019642,
.013928,.0185,
.014518,.017236,
.014878,.015889,
.015,.0145,
.015,-.0145,
.014878,-.015889,
.014518,-.017236,
.013928,-.0185,
.013128,-.019642,
.012142,-.020628,
.011,-.021428,
.009736,-.022018,
.008389,-.022378,
.007,-.0225,
-.007,-.0225,
0.0*
%
%ADD78MACRO78*%
%AMMACRO25*
4,1,40,.007,.011,
-.007,.011,
-.007695,.010939,
-.008368,.010759,
-.009,.010464,
-.009571,.010064,
-.010064,.009571,
-.010464,.009,
-.010759,.008368,
-.010939,.007695,
-.011,.007,
-.011,-.007,
-.010939,-.007695,
-.010759,-.008368,
-.010464,-.009,
-.010064,-.009571,
-.009571,-.010064,
-.009,-.010464,
-.008368,-.010759,
-.007695,-.010939,
-.007,-.011,
.007,-.011,
.007695,-.010939,
.008368,-.010759,
.009,-.010464,
.009571,-.010064,
.010064,-.009571,
.010464,-.009,
.010759,-.008368,
.010939,-.007695,
.011,-.007,
.011,.007,
.010939,.007695,
.010759,.008368,
.010464,.009,
.010064,.009571,
.009571,.010064,
.009,.010464,
.008368,.010759,
.007695,.010939,
.007,.011,
0.0*
%
%ADD25MACRO25*%
%AMMACRO14*
4,1,40,.011,-.007,
.011,.007,
.010939,.007695,
.010759,.008368,
.010464,.009,
.010064,.009571,
.009571,.010064,
.009,.010464,
.008368,.010759,
.007695,.010939,
.007,.011,
-.007,.011,
-.007695,.010939,
-.008368,.010759,
-.009,.010464,
-.009571,.010064,
-.010064,.009571,
-.010464,.009,
-.010759,.008368,
-.010939,.007695,
-.011,.007,
-.011,-.007,
-.010939,-.007695,
-.010759,-.008368,
-.010464,-.009,
-.010064,-.009571,
-.009571,-.010064,
-.009,-.010464,
-.008368,-.010759,
-.007695,-.010939,
-.007,-.011,
.007,-.011,
.007695,-.010939,
.008368,-.010759,
.009,-.010464,
.009571,-.010064,
.010064,-.009571,
.010464,-.009,
.010759,-.008368,
.010939,-.007695,
.011,-.007,
0.0*
%
%ADD14MACRO14*%
%AMMACRO34*
4,1,40,-.012,.008,
-.012,-.008,
-.011939,-.008695,
-.011759,-.009368,
-.011464,-.01,
-.011064,-.010571,
-.010571,-.011064,
-.01,-.011464,
-.009368,-.011759,
-.008695,-.011939,
-.008,-.012,
.008,-.012,
.008695,-.011939,
.009368,-.011759,
.01,-.011464,
.010571,-.011064,
.011064,-.010571,
.011464,-.01,
.011759,-.009368,
.011939,-.008695,
.012,-.008,
.012,.008,
.011939,.008695,
.011759,.009368,
.011464,.01,
.011064,.010571,
.010571,.011064,
.01,.011464,
.009368,.011759,
.008695,.011939,
.008,.012,
-.008,.012,
-.008695,.011939,
-.009368,.011759,
-.01,.011464,
-.010571,.011064,
-.011064,.010571,
-.011464,.01,
-.011759,.009368,
-.011939,.008695,
-.012,.008,
0.0*
%
%ADD34MACRO34*%
%AMMACRO36*
4,1,40,.008,.012,
-.008,.012,
-.008695,.011939,
-.009368,.011759,
-.01,.011464,
-.010571,.011064,
-.011064,.010571,
-.011464,.01,
-.011759,.009368,
-.011939,.008695,
-.012,.008,
-.012,-.008,
-.011939,-.008695,
-.011759,-.009368,
-.011464,-.01,
-.011064,-.010571,
-.010571,-.011064,
-.01,-.011464,
-.009368,-.011759,
-.008695,-.011939,
-.008,-.012,
.008,-.012,
.008695,-.011939,
.009368,-.011759,
.01,-.011464,
.010571,-.011064,
.011064,-.010571,
.011464,-.01,
.011759,-.009368,
.011939,-.008695,
.012,-.008,
.012,.008,
.011939,.008695,
.011759,.009368,
.011464,.01,
.011064,.010571,
.010571,.011064,
.01,.011464,
.009368,.011759,
.008695,.011939,
.008,.012,
0.0*
%
%ADD36MACRO36*%
%AMMACRO87*
4,1,40,-.013,-.017,
.013,-.017,
.013695,-.016939,
.014368,-.016759,
.015,-.016464,
.015571,-.016064,
.016064,-.015571,
.016464,-.015,
.016759,-.014368,
.016939,-.013695,
.017,-.013,
.017,.013,
.016939,.013695,
.016759,.014368,
.016464,.015,
.016064,.015571,
.015571,.016064,
.015,.016464,
.014368,.016759,
.013695,.016939,
.013,.017,
-.013,.017,
-.013695,.016939,
-.014368,.016759,
-.015,.016464,
-.015571,.016064,
-.016064,.015571,
-.016464,.015,
-.016759,.014368,
-.016939,.013695,
-.017,.013,
-.017,-.013,
-.016939,-.013695,
-.016759,-.014368,
-.016464,-.015,
-.016064,-.015571,
-.015571,-.016064,
-.015,-.016464,
-.014368,-.016759,
-.013695,-.016939,
-.013,-.017,
0.0*
%
%ADD87MACRO87*%
%AMMACRO93*
4,1,40,-.017,.013,
-.017,-.013,
-.016939,-.013695,
-.016759,-.014368,
-.016464,-.015,
-.016064,-.015571,
-.015571,-.016064,
-.015,-.016464,
-.014368,-.016759,
-.013695,-.016939,
-.013,-.017,
.013,-.017,
.013695,-.016939,
.014368,-.016759,
.015,-.016464,
.015571,-.016064,
.016064,-.015571,
.016464,-.015,
.016759,-.014368,
.016939,-.013695,
.017,-.013,
.017,.013,
.016939,.013695,
.016759,.014368,
.016464,.015,
.016064,.015571,
.015571,.016064,
.015,.016464,
.014368,.016759,
.013695,.016939,
.013,.017,
-.013,.017,
-.013695,.016939,
-.014368,.016759,
-.015,.016464,
-.015571,.016064,
-.016064,.015571,
-.016464,.015,
-.016759,.014368,
-.016939,.013695,
-.017,.013,
0.0*
%
%ADD93MACRO93*%
%AMMACRO83*
4,1,40,-.009,.008,
-.008939,.008695,
-.008759,.009368,
-.008464,.01,
-.008064,.010571,
-.007571,.011064,
-.007,.011464,
-.006368,.011759,
-.005695,.011939,
-.005,.012,
.005,.012,
.005695,.011939,
.006368,.011759,
.007,.011464,
.007571,.011064,
.008064,.010571,
.008464,.01,
.008759,.009368,
.008939,.008695,
.009,.008,
.009,-.008,
.008939,-.008695,
.008759,-.009368,
.008464,-.01,
.008064,-.010571,
.007571,-.011064,
.007,-.011464,
.006368,-.011759,
.005695,-.011939,
.005,-.012,
-.005,-.012,
-.005695,-.011939,
-.006368,-.011759,
-.007,-.011464,
-.007571,-.011064,
-.008064,-.010571,
-.008464,-.01,
-.008759,-.009368,
-.008939,-.008695,
-.009,-.008,
-.009,.008,
0.0*
%
%ADD83MACRO83*%
%AMMACRO124*
4,1,6,-.0135,.005,
-.0065,.005,
.0135,.025,
.0135,-.025,
-.0065,-.005,
-.0135,-.005,
-.0135,.005,
0.0*
%
%ADD124MACRO124*%
%AMMACRO84*
4,1,40,.008,.009,
.008695,.008939,
.009368,.008759,
.01,.008464,
.010571,.008064,
.011064,.007571,
.011464,.007,
.011759,.006368,
.011939,.005695,
.012,.005,
.012,-.005,
.011939,-.005695,
.011759,-.006368,
.011464,-.007,
.011064,-.007571,
.010571,-.008064,
.01,-.008464,
.009368,-.008759,
.008695,-.008939,
.008,-.009,
-.008,-.009,
-.008695,-.008939,
-.009368,-.008759,
-.01,-.008464,
-.010571,-.008064,
-.011064,-.007571,
-.011464,-.007,
-.011759,-.006368,
-.011939,-.005695,
-.012,-.005,
-.012,.005,
-.011939,.005695,
-.011759,.006368,
-.011464,.007,
-.011064,.007571,
-.010571,.008064,
-.01,.008464,
-.009368,.008759,
-.008695,.008939,
-.008,.009,
.008,.009,
0.0*
%
%ADD84MACRO84*%
%AMMACRO47*
4,1,6,.005,.0135,
.005,.0065,
.025,-.0135,
-.025,-.0135,
-.005,.0065,
-.005,.0135,
.005,.0135,
0.0*
%
%ADD47MACRO47*%
%AMMACRO26*
4,1,40,.007,.011,
-.007,.011,
-.007695,.010939,
-.008368,.010759,
-.009,.010464,
-.009571,.010064,
-.010064,.009571,
-.010464,.009,
-.010759,.008368,
-.010939,.007695,
-.011,.007,
-.011,-.007,
-.010939,-.007695,
-.010759,-.008368,
-.010464,-.009,
-.010064,-.009571,
-.009571,-.010064,
-.009,-.010464,
-.008368,-.010759,
-.007695,-.010939,
-.007,-.011,
.007,-.011,
.007695,-.010939,
.008368,-.010759,
.009,-.010464,
.009571,-.010064,
.010064,-.009571,
.010464,-.009,
.010759,-.008368,
.010939,-.007695,
.011,-.007,
.011,.007,
.010939,.007695,
.010759,.008368,
.010464,.009,
.010064,.009571,
.009571,.010064,
.009,.010464,
.008368,.010759,
.007695,.010939,
.007,.011,
0.0*
%
%ADD26MACRO26*%
%AMMACRO15*
4,1,40,.011,-.007,
.011,.007,
.010939,.007695,
.010759,.008368,
.010464,.009,
.010064,.009571,
.009571,.010064,
.009,.010464,
.008368,.010759,
.007695,.010939,
.007,.011,
-.007,.011,
-.007695,.010939,
-.008368,.010759,
-.009,.010464,
-.009571,.010064,
-.010064,.009571,
-.010464,.009,
-.010759,.008368,
-.010939,.007695,
-.011,.007,
-.011,-.007,
-.010939,-.007695,
-.010759,-.008368,
-.010464,-.009,
-.010064,-.009571,
-.009571,-.010064,
-.009,-.010464,
-.008368,-.010759,
-.007695,-.010939,
-.007,-.011,
.007,-.011,
.007695,-.010939,
.008368,-.010759,
.009,-.010464,
.009571,-.010064,
.010064,-.009571,
.010464,-.009,
.010759,-.008368,
.010939,-.007695,
.011,-.007,
0.0*
%
%ADD15MACRO15*%
%AMMACRO133*
4,1,20,-.1075,-.0635,
-.1075,-.049,
-.118,-.049,
-.118,-.0395,
-.1075,-.0395,
-.1075,.0395,
-.118,.0395,
-.118,.049,
-.1075,.049,
-.1075,.0635,
.1075,.0635,
.1075,.049,
.118,.049,
.118,.0395,
.1075,.0395,
.1075,-.0395,
.118,-.0395,
.118,-.049,
.1075,-.049,
.1075,-.0635,
-.1075,-.0635,
0.0*
%
%ADD133MACRO133*%
%AMMACRO33*
4,1,40,-.012,.008,
-.012,-.008,
-.011939,-.008695,
-.011759,-.009368,
-.011464,-.01,
-.011064,-.010571,
-.010571,-.011064,
-.01,-.011464,
-.009368,-.011759,
-.008695,-.011939,
-.008,-.012,
.008,-.012,
.008695,-.011939,
.009368,-.011759,
.01,-.011464,
.010571,-.011064,
.011064,-.010571,
.011464,-.01,
.011759,-.009368,
.011939,-.008695,
.012,-.008,
.012,.008,
.011939,.008695,
.011759,.009368,
.011464,.01,
.011064,.010571,
.010571,.011064,
.01,.011464,
.009368,.011759,
.008695,.011939,
.008,.012,
-.008,.012,
-.008695,.011939,
-.009368,.011759,
-.01,.011464,
-.010571,.011064,
-.011064,.010571,
-.011464,.01,
-.011759,.009368,
-.011939,.008695,
-.012,.008,
0.0*
%
%ADD33MACRO33*%
%AMMACRO35*
4,1,40,.008,.012,
-.008,.012,
-.008695,.011939,
-.009368,.011759,
-.01,.011464,
-.010571,.011064,
-.011064,.010571,
-.011464,.01,
-.011759,.009368,
-.011939,.008695,
-.012,.008,
-.012,-.008,
-.011939,-.008695,
-.011759,-.009368,
-.011464,-.01,
-.011064,-.010571,
-.010571,-.011064,
-.01,-.011464,
-.009368,-.011759,
-.008695,-.011939,
-.008,-.012,
.008,-.012,
.008695,-.011939,
.009368,-.011759,
.01,-.011464,
.010571,-.011064,
.011064,-.010571,
.011464,-.01,
.011759,-.009368,
.011939,-.008695,
.012,-.008,
.012,.008,
.011939,.008695,
.011759,.009368,
.011464,.01,
.011064,.010571,
.010571,.011064,
.01,.011464,
.009368,.011759,
.008695,.011939,
.008,.012,
0.0*
%
%ADD35MACRO35*%
%AMMACRO88*
4,1,40,-.013,-.017,
.013,-.017,
.013695,-.016939,
.014368,-.016759,
.015,-.016464,
.015571,-.016064,
.016064,-.015571,
.016464,-.015,
.016759,-.014368,
.016939,-.013695,
.017,-.013,
.017,.013,
.016939,.013695,
.016759,.014368,
.016464,.015,
.016064,.015571,
.015571,.016064,
.015,.016464,
.014368,.016759,
.013695,.016939,
.013,.017,
-.013,.017,
-.013695,.016939,
-.014368,.016759,
-.015,.016464,
-.015571,.016064,
-.016064,.015571,
-.016464,.015,
-.016759,.014368,
-.016939,.013695,
-.017,.013,
-.017,-.013,
-.016939,-.013695,
-.016759,-.014368,
-.016464,-.015,
-.016064,-.015571,
-.015571,-.016064,
-.015,-.016464,
-.014368,-.016759,
-.013695,-.016939,
-.013,-.017,
0.0*
%
%ADD88MACRO88*%
%AMMACRO94*
4,1,40,-.017,.013,
-.017,-.013,
-.016939,-.013695,
-.016759,-.014368,
-.016464,-.015,
-.016064,-.015571,
-.015571,-.016064,
-.015,-.016464,
-.014368,-.016759,
-.013695,-.016939,
-.013,-.017,
.013,-.017,
.013695,-.016939,
.014368,-.016759,
.015,-.016464,
.015571,-.016064,
.016064,-.015571,
.016464,-.015,
.016759,-.014368,
.016939,-.013695,
.017,-.013,
.017,.013,
.016939,.013695,
.016759,.014368,
.016464,.015,
.016064,.015571,
.015571,.016064,
.015,.016464,
.014368,.016759,
.013695,.016939,
.013,.017,
-.013,.017,
-.013695,.016939,
-.014368,.016759,
-.015,.016464,
-.015571,.016064,
-.016064,.015571,
-.016464,.015,
-.016759,.014368,
-.016939,.013695,
-.017,.013,
0.0*
%
%ADD94MACRO94*%
%AMMACRO82*
4,1,40,.009,-.008,
.008939,-.008695,
.008759,-.009368,
.008464,-.01,
.008064,-.010571,
.007571,-.011064,
.007,-.011464,
.006368,-.011759,
.005695,-.011939,
.005,-.012,
-.005,-.012,
-.005695,-.011939,
-.006368,-.011759,
-.007,-.011464,
-.007571,-.011064,
-.008064,-.010571,
-.008464,-.01,
-.008759,-.009368,
-.008939,-.008695,
-.009,-.008,
-.009,.008,
-.008939,.008695,
-.008759,.009368,
-.008464,.01,
-.008064,.010571,
-.007571,.011064,
-.007,.011464,
-.006368,.011759,
-.005695,.011939,
-.005,.012,
.005,.012,
.005695,.011939,
.006368,.011759,
.007,.011464,
.007571,.011064,
.008064,.010571,
.008464,.01,
.008759,.009368,
.008939,.008695,
.009,.008,
.009,-.008,
0.0*
%
%ADD82MACRO82*%
%ADD141R,.011X.03*%
%ADD140R,.03X.011*%
%AMMACRO90*
4,1,40,-.008,-.009,
-.008695,-.008939,
-.009368,-.008759,
-.01,-.008464,
-.010571,-.008064,
-.011064,-.007571,
-.011464,-.007,
-.011759,-.006368,
-.011939,-.005695,
-.012,-.005,
-.012,.005,
-.011939,.005695,
-.011759,.006368,
-.011464,.007,
-.011064,.007571,
-.010571,.008064,
-.01,.008464,
-.009368,.008759,
-.008695,.008939,
-.008,.009,
.008,.009,
.008695,.008939,
.009368,.008759,
.01,.008464,
.010571,.008064,
.011064,.007571,
.011464,.007,
.011759,.006368,
.011939,.005695,
.012,.005,
.012,-.005,
.011939,-.005695,
.011759,-.006368,
.011464,-.007,
.011064,-.007571,
.010571,-.008064,
.01,-.008464,
.009368,-.008759,
.008695,-.008939,
.008,-.009,
-.008,-.009,
0.0*
%
%ADD90MACRO90*%
%ADD99R,.05X.012*%
%ADD98R,.012X.05*%
%ADD89R,.06X.02*%
%ADD69R,.04X.022*%
%ADD104R,.042X.012*%
%ADD102R,.012X.042*%
%ADD77R,.06X.012*%
%ADD19R,.022X.04*%
%ADD121R,.012X.06*%
%ADD97R,.043X.012*%
%ADD96R,.012X.043*%
%ADD75R,.06X.014*%
%ADD72R,.081X.02*%
%ADD62R,.04X.016*%
%ADD50R,.044X.012*%
%ADD38R,.042X.014*%
%ADD32R,.014X.042*%
%ADD142R,.032X.016*%
%ADD134R,.012X.044*%
%ADD120R,.014X.06*%
%ADD103R,.036X.012*%
%ADD101R,.012X.036*%
%ADD61R,.105X.128*%
%ADD129R,.012X.036*%
%ADD127R,.036X.012*%
%ADD114R,.016X.032*%
%ADD108R,.064X.03*%
%ADD107R,.03X.045*%
%ADD42C,.13*%
%ADD138R,.093X.011*%
%ADD135R,.128X.133*%
%ADD130R,.012X.037*%
%ADD128R,.037X.012*%
%ADD40R,.066X.02*%
%ADD116C,.15*%
%ADD71O,.06X.084*%
%ADD68R,.05X.065*%
%ADD95R,.055X.042*%
%ADD81R,.026X.036*%
%ADD22O,.268X.134*%
%ADD20R,.065X.05*%
%ADD144R,.029X.043*%
%ADD41R,.065X.025*%
%ADD112R,.09X.045*%
%ADD91R,.025X.065*%
%ADD76R,.048X.016*%
%ADD44R,.045X.055*%
%ADD119C,.119*%
%ADD105R,.13X.13*%
%ADD65R,.016X.048*%
%ADD43R,.055X.036*%
%ADD31R,.055X.045*%
%ADD145R,.06X.095*%
%ADD132R,.054X.074*%
%ADD54C,.256*%
%ADD131R,.09X.095*%
%ADD92R,.059X.045*%
%ADD59R,.024X.079*%
%AMMACRO115*
4,1,40,.007,.0225,
.008389,.022378,
.009736,.022018,
.011,.021428,
.012142,.020628,
.013128,.019642,
.013928,.0185,
.014518,.017236,
.014878,.015889,
.015,.0145,
.015,-.0145,
.014878,-.015889,
.014518,-.017236,
.013928,-.0185,
.013128,-.019642,
.012142,-.020628,
.011,-.021428,
.009736,-.022018,
.008389,-.022378,
.007,-.0225,
-.007,-.0225,
-.008389,-.022378,
-.009736,-.022018,
-.011,-.021428,
-.012142,-.020628,
-.013128,-.019642,
-.013928,-.0185,
-.014518,-.017236,
-.014878,-.015889,
-.015,-.0145,
-.015,.0145,
-.014878,.015889,
-.014518,.017236,
-.013928,.0185,
-.013128,.019642,
-.012142,.020628,
-.011,.021428,
-.009736,.022018,
-.008389,.022378,
-.007,.0225,
.007,.0225,
0.0*
%
%ADD115MACRO115*%
%ADD109R,.045X.059*%
%ADD100R,.152X.152*%
%AMMACRO79*
4,1,40,.014,.008,
.014,-.008,
.013939,-.008695,
.013759,-.009368,
.013464,-.01,
.013064,-.010571,
.012571,-.011064,
.012,-.011464,
.011368,-.011759,
.010695,-.011939,
.01,-.012,
-.01,-.012,
-.010695,-.011939,
-.011368,-.011759,
-.012,-.011464,
-.012571,-.011064,
-.013064,-.010571,
-.013464,-.01,
-.013759,-.009368,
-.013939,-.008695,
-.014,-.008,
-.014,.008,
-.013939,.008695,
-.013759,.009368,
-.013464,.01,
-.013064,.010571,
-.012571,.011064,
-.012,.011464,
-.011368,.011759,
-.010695,.011939,
-.01,.012,
.01,.012,
.010695,.011939,
.011368,.011759,
.012,.011464,
.012571,.011064,
.013064,.010571,
.013464,.01,
.013759,.009368,
.013939,.008695,
.014,.008,
0.0*
%
%ADD79MACRO79*%
%AMMACRO67*
4,1,40,-.008,.014,
.008,.014,
.008695,.013939,
.009368,.013759,
.01,.013464,
.010571,.013064,
.011064,.012571,
.011464,.012,
.011759,.011368,
.011939,.010695,
.012,.01,
.012,-.01,
.011939,-.010695,
.011759,-.011368,
.011464,-.012,
.011064,-.012571,
.010571,-.013064,
.01,-.013464,
.009368,-.013759,
.008695,-.013939,
.008,-.014,
-.008,-.014,
-.008695,-.013939,
-.009368,-.013759,
-.01,-.013464,
-.010571,-.013064,
-.011064,-.012571,
-.011464,-.012,
-.011759,-.011368,
-.011939,-.010695,
-.012,-.01,
-.012,.01,
-.011939,.010695,
-.011759,.011368,
-.011464,.012,
-.011064,.012571,
-.010571,.013064,
-.01,.013464,
-.009368,.013759,
-.008695,.013939,
-.008,.014,
0.0*
%
%ADD67MACRO67*%
%AMMACRO63*
4,1,40,-.0225,.007,
-.022378,.008389,
-.022018,.009736,
-.021428,.011,
-.020628,.012142,
-.019642,.013128,
-.0185,.013928,
-.017236,.014518,
-.015889,.014878,
-.0145,.015,
.0145,.015,
.015889,.014878,
.017236,.014518,
.0185,.013928,
.019642,.013128,
.020628,.012142,
.021428,.011,
.022018,.009736,
.022378,.008389,
.0225,.007,
.0225,-.007,
.022378,-.008389,
.022018,-.009736,
.021428,-.011,
.020628,-.012142,
.019642,-.013128,
.0185,-.013928,
.017236,-.014518,
.015889,-.014878,
.0145,-.015,
-.0145,-.015,
-.015889,-.014878,
-.017236,-.014518,
-.0185,-.013928,
-.019642,-.013128,
-.020628,-.012142,
-.021428,-.011,
-.022018,-.009736,
-.022378,-.008389,
-.0225,-.007,
-.0225,.007,
0.0*
%
%ADD63MACRO63*%
%ADD60R,.095X.09*%
%ADD21C,.375*%
%ADD123R,.069X.083*%
%ADD37R,.128X.128*%
%AMMACRO53*
4,1,40,-.008,-.012,
.008,-.012,
.008695,-.011939,
.009368,-.011759,
.01,-.011464,
.010571,-.011064,
.011064,-.010571,
.011464,-.01,
.011759,-.009368,
.011939,-.008695,
.012,-.008,
.012,.008,
.011939,.008695,
.011759,.009368,
.011464,.01,
.011064,.010571,
.010571,.011064,
.01,.011464,
.009368,.011759,
.008695,.011939,
.008,.012,
-.008,.012,
-.008695,.011939,
-.009368,.011759,
-.01,.011464,
-.010571,.011064,
-.011064,.010571,
-.011464,.01,
-.011759,.009368,
-.011939,.008695,
-.012,.008,
-.012,-.008,
-.011939,-.008695,
-.011759,-.009368,
-.011464,-.01,
-.011064,-.010571,
-.010571,-.011064,
-.01,-.011464,
-.009368,-.011759,
-.008695,-.011939,
-.008,-.012,
0.0*
%
%ADD53MACRO53*%
%AMMACRO30*
4,1,40,.012,-.008,
.012,.008,
.011939,.008695,
.011759,.009368,
.011464,.01,
.011064,.010571,
.010571,.011064,
.01,.011464,
.009368,.011759,
.008695,.011939,
.008,.012,
-.008,.012,
-.008695,.011939,
-.009368,.011759,
-.01,.011464,
-.010571,.011064,
-.011064,.010571,
-.011464,.01,
-.011759,.009368,
-.011939,.008695,
-.012,.008,
-.012,-.008,
-.011939,-.008695,
-.011759,-.009368,
-.011464,-.01,
-.011064,-.010571,
-.010571,-.011064,
-.01,-.011464,
-.009368,-.011759,
-.008695,-.011939,
-.008,-.012,
.008,-.012,
.008695,-.011939,
.009368,-.011759,
.01,-.011464,
.010571,-.011064,
.011064,-.010571,
.011464,-.01,
.011759,-.009368,
.011939,-.008695,
.012,-.008,
0.0*
%
%ADD30MACRO30*%
%AMMACRO23*
4,1,40,-.007,-.011,
.007,-.011,
.007695,-.010939,
.008368,-.010759,
.009,-.010464,
.009571,-.010064,
.010064,-.009571,
.010464,-.009,
.010759,-.008368,
.010939,-.007695,
.011,-.007,
.011,.007,
.010939,.007695,
.010759,.008368,
.010464,.009,
.010064,.009571,
.009571,.010064,
.009,.010464,
.008368,.010759,
.007695,.010939,
.007,.011,
-.007,.011,
-.007695,.010939,
-.008368,.010759,
-.009,.010464,
-.009571,.010064,
-.010064,.009571,
-.010464,.009,
-.010759,.008368,
-.010939,.007695,
-.011,.007,
-.011,-.007,
-.010939,-.007695,
-.010759,-.008368,
-.010464,-.009,
-.010064,-.009571,
-.009571,-.010064,
-.009,-.010464,
-.008368,-.010759,
-.007695,-.010939,
-.007,-.011,
0.0*
%
%ADD23MACRO23*%
%AMMACRO12*
4,1,40,-.011,.007,
-.011,-.007,
-.010939,-.007695,
-.010759,-.008368,
-.010464,-.009,
-.010064,-.009571,
-.009571,-.010064,
-.009,-.010464,
-.008368,-.010759,
-.007695,-.010939,
-.007,-.011,
.007,-.011,
.007695,-.010939,
.008368,-.010759,
.009,-.010464,
.009571,-.010064,
.010064,-.009571,
.010464,-.009,
.010759,-.008368,
.010939,-.007695,
.011,-.007,
.011,.007,
.010939,.007695,
.010759,.008368,
.010464,.009,
.010064,.009571,
.009571,.010064,
.009,.010464,
.008368,.010759,
.007695,.010939,
.007,.011,
-.007,.011,
-.007695,.010939,
-.008368,.010759,
-.009,.010464,
-.009571,.010064,
-.010064,.009571,
-.010464,.009,
-.010759,.008368,
-.010939,.007695,
-.011,.007,
0.0*
%
%ADD12MACRO12*%
%AMMACRO125*
4,1,6,-.0135,.025,
.0065,.005,
.0135,.005,
.0135,-.005,
.0065,-.005,
-.0135,-.025,
-.0135,.025,
0.0*
%
%ADD125MACRO125*%
%AMMACRO55*
4,1,40,.013,.017,
-.013,.017,
-.013695,.016939,
-.014368,.016759,
-.015,.016464,
-.015571,.016064,
-.016064,.015571,
-.016464,.015,
-.016759,.014368,
-.016939,.013695,
-.017,.013,
-.017,-.013,
-.016939,-.013695,
-.016759,-.014368,
-.016464,-.015,
-.016064,-.015571,
-.015571,-.016064,
-.015,-.016464,
-.014368,-.016759,
-.013695,-.016939,
-.013,-.017,
.013,-.017,
.013695,-.016939,
.014368,-.016759,
.015,-.016464,
.015571,-.016064,
.016064,-.015571,
.016464,-.015,
.016759,-.014368,
.016939,-.013695,
.017,-.013,
.017,.013,
.016939,.013695,
.016759,.014368,
.016464,.015,
.016064,.015571,
.015571,.016064,
.015,.016464,
.014368,.016759,
.013695,.016939,
.013,.017,
0.0*
%
%ADD55MACRO55*%
%AMMACRO48*
4,1,6,.025,.0135,
.005,-.0065,
.005,-.0135,
-.005,-.0135,
-.005,-.0065,
-.025,.0135,
.025,.0135,
0.0*
%
%ADD48MACRO48*%
%AMMACRO16*
4,1,40,.017,-.013,
.017,.013,
.016939,.013695,
.016759,.014368,
.016464,.015,
.016064,.015571,
.015571,.016064,
.015,.016464,
.014368,.016759,
.013695,.016939,
.013,.017,
-.013,.017,
-.013695,.016939,
-.014368,.016759,
-.015,.016464,
-.015571,.016064,
-.016064,.015571,
-.016464,.015,
-.016759,.014368,
-.016939,.013695,
-.017,.013,
-.017,-.013,
-.016939,-.013695,
-.016759,-.014368,
-.016464,-.015,
-.016064,-.015571,
-.015571,-.016064,
-.015,-.016464,
-.014368,-.016759,
-.013695,-.016939,
-.013,-.017,
.013,-.017,
.013695,-.016939,
.014368,-.016759,
.015,-.016464,
.015571,-.016064,
.016064,-.015571,
.016464,-.015,
.016759,-.014368,
.016939,-.013695,
.017,-.013,
0.0*
%
%ADD16MACRO16*%
%AMMACRO86*
4,1,40,-.008,-.009,
-.008695,-.008939,
-.009368,-.008759,
-.01,-.008464,
-.010571,-.008064,
-.011064,-.007571,
-.011464,-.007,
-.011759,-.006368,
-.011939,-.005695,
-.012,-.005,
-.012,.005,
-.011939,.005695,
-.011759,.006368,
-.011464,.007,
-.011064,.007571,
-.010571,.008064,
-.01,.008464,
-.009368,.008759,
-.008695,.008939,
-.008,.009,
.008,.009,
.008695,.008939,
.009368,.008759,
.01,.008464,
.010571,.008064,
.011064,.007571,
.011464,.007,
.011759,.006368,
.011939,.005695,
.012,.005,
.012,-.005,
.011939,-.005695,
.011759,-.006368,
.011464,-.007,
.011064,-.007571,
.010571,-.008064,
.01,-.008464,
.009368,-.008759,
.008695,-.008939,
.008,-.009,
-.008,-.009,
0.0*
%
%ADD86MACRO86*%
%AMMACRO49*
4,1,20,-.0635,.1075,
-.049,.1075,
-.049,.118,
-.0395,.118,
-.0395,.1075,
.0395,.1075,
.0395,.118,
.049,.118,
.049,.1075,
.0635,.1075,
.0635,-.1075,
.049,-.1075,
.049,-.118,
.0395,-.118,
.0395,-.1075,
-.0395,-.1075,
-.0395,-.118,
-.049,-.118,
-.049,-.1075,
-.0635,-.1075,
-.0635,.1075,
0.0*
%
%ADD49MACRO49*%
%AMMACRO57*
4,1,15,-.0275,-.115,
-.0275,.115,
.0275,.115,
.0275,.06339,
.02431,.059697,
.021809,.055506,
.020074,.050945,
.019157,.046151,
.019087,.041272,
.019865,.036454,
.021468,.031844,
.023847,.027583,
.02693,.0238,
.0275,.02323,
.0275,-.115,
-.0275,-.115,
0.0*
%
%ADD57MACRO57*%
%AMMACRO52*
4,1,40,-.008,-.012,
.008,-.012,
.008695,-.011939,
.009368,-.011759,
.01,-.011464,
.010571,-.011064,
.011064,-.010571,
.011464,-.01,
.011759,-.009368,
.011939,-.008695,
.012,-.008,
.012,.008,
.011939,.008695,
.011759,.009368,
.011464,.01,
.011064,.010571,
.010571,.011064,
.01,.011464,
.009368,.011759,
.008695,.011939,
.008,.012,
-.008,.012,
-.008695,.011939,
-.009368,.011759,
-.01,.011464,
-.010571,.011064,
-.011064,.010571,
-.011464,.01,
-.011759,.009368,
-.011939,.008695,
-.012,.008,
-.012,-.008,
-.011939,-.008695,
-.011759,-.009368,
-.011464,-.01,
-.011064,-.010571,
-.010571,-.011064,
-.01,-.011464,
-.009368,-.011759,
-.008695,-.011939,
-.008,-.012,
0.0*
%
%ADD52MACRO52*%
%AMMACRO29*
4,1,40,.012,-.008,
.012,.008,
.011939,.008695,
.011759,.009368,
.011464,.01,
.011064,.010571,
.010571,.011064,
.01,.011464,
.009368,.011759,
.008695,.011939,
.008,.012,
-.008,.012,
-.008695,.011939,
-.009368,.011759,
-.01,.011464,
-.010571,.011064,
-.011064,.010571,
-.011464,.01,
-.011759,.009368,
-.011939,.008695,
-.012,.008,
-.012,-.008,
-.011939,-.008695,
-.011759,-.009368,
-.011464,-.01,
-.011064,-.010571,
-.010571,-.011064,
-.01,-.011464,
-.009368,-.011759,
-.008695,-.011939,
-.008,-.012,
.008,-.012,
.008695,-.011939,
.009368,-.011759,
.01,-.011464,
.010571,-.011064,
.011064,-.010571,
.011464,-.01,
.011759,-.009368,
.011939,-.008695,
.012,-.008,
0.0*
%
%ADD29MACRO29*%
%AMMACRO24*
4,1,40,-.007,-.011,
.007,-.011,
.007695,-.010939,
.008368,-.010759,
.009,-.010464,
.009571,-.010064,
.010064,-.009571,
.010464,-.009,
.010759,-.008368,
.010939,-.007695,
.011,-.007,
.011,.007,
.010939,.007695,
.010759,.008368,
.010464,.009,
.010064,.009571,
.009571,.010064,
.009,.010464,
.008368,.010759,
.007695,.010939,
.007,.011,
-.007,.011,
-.007695,.010939,
-.008368,.010759,
-.009,.010464,
-.009571,.010064,
-.010064,.009571,
-.010464,.009,
-.010759,.008368,
-.010939,.007695,
-.011,.007,
-.011,-.007,
-.010939,-.007695,
-.010759,-.008368,
-.010464,-.009,
-.010064,-.009571,
-.009571,-.010064,
-.009,-.010464,
-.008368,-.010759,
-.007695,-.010939,
-.007,-.011,
0.0*
%
%ADD24MACRO24*%
%AMMACRO13*
4,1,40,-.011,.007,
-.011,-.007,
-.010939,-.007695,
-.010759,-.008368,
-.010464,-.009,
-.010064,-.009571,
-.009571,-.010064,
-.009,-.010464,
-.008368,-.010759,
-.007695,-.010939,
-.007,-.011,
.007,-.011,
.007695,-.010939,
.008368,-.010759,
.009,-.010464,
.009571,-.010064,
.010064,-.009571,
.010464,-.009,
.010759,-.008368,
.010939,-.007695,
.011,-.007,
.011,.007,
.010939,.007695,
.010759,.008368,
.010464,.009,
.010064,.009571,
.009571,.010064,
.009,.010464,
.008368,.010759,
.007695,.010939,
.007,.011,
-.007,.011,
-.007695,.010939,
-.008368,.010759,
-.009,.010464,
-.009571,.010064,
-.010064,.009571,
-.010464,.009,
-.010759,.008368,
-.010939,.007695,
-.011,.007,
0.0*
%
%ADD13MACRO13*%
%ADD146C,.006*%
G75*
%LPD*%
G75*
G36*
G01X533408Y30785D02*
Y22235D01*
X542358D01*
Y30785D01*
X533408D01*
G37*
G36*
G01Y41935D02*
Y33385D01*
X542358D01*
Y41935D01*
X533408D01*
G37*
G36*
G01X544958Y30785D02*
Y22235D01*
X553908D01*
Y30785D01*
X544958D01*
G37*
G36*
G01Y41935D02*
Y33385D01*
X553908D01*
Y41935D01*
X544958D01*
G37*
G54D100*
X365164Y612620D03*
G54D101*
X461110Y45450D03*
Y25350D03*
X474890Y45450D03*
Y25350D03*
G54D110*
X488838Y137225D03*
G54D120*
X625894Y360600D03*
X628454D03*
X631014D03*
X633574D03*
Y347800D03*
X631014D03*
X628454D03*
X625894D03*
G54D102*
X463079Y45150D03*
X465047D03*
X467016D03*
X468984D03*
X470953D03*
Y25650D03*
X468984D03*
X467016D03*
X465047D03*
X463079D03*
X472921Y45150D03*
Y25650D03*
G54D111*
X488838Y164744D03*
G54D112*
X542550Y54803D03*
Y48397D03*
G54D130*
X628144Y531987D03*
X626176D03*
Y544099D03*
X628144D03*
G54D103*
X457950Y28510D03*
Y42290D03*
X478050D03*
Y28510D03*
G54D121*
X613087Y359016D03*
X615057D03*
X617027D03*
X618997D03*
Y349816D03*
X617027D03*
X615057D03*
X613087D03*
G54D10*
G01X-13131Y-65072D02*
Y-145072D01*
G01D02*
X1244069D01*
G01X-29131Y-65072D02*
Y-33072D01*
G01X-13131Y-65072D02*
X1244069D01*
G01X-13131Y-100572D02*
X1244069D01*
G01X-17131Y-49072D02*
G02I-12000J0D01*
G01X-22281D02*
G02I-6850J0D01*
G01X-13131D02*
X-45131D01*
G01X456569Y-65072D02*
Y-145072D01*
G01X594069Y-65072D02*
Y-145072D01*
G01X709069Y-65072D02*
Y-145072D01*
G01X876569Y-65072D02*
Y-145072D01*
G01X1046569Y-65072D02*
Y-145072D01*
G01X1244069Y-65072D02*
Y-145072D01*
G01X1272069Y-49072D02*
G02I-12000J0D01*
G01X1266919D02*
G02I-6850J0D01*
G01X1276069D02*
X1244069D01*
G01X1260069Y-65072D02*
Y-33072D01*
X8500Y18279D03*
Y28279D03*
Y38279D03*
Y48279D03*
Y58279D03*
Y68279D03*
X13721Y8500D03*
X8500Y13279D03*
Y23279D03*
Y33279D03*
Y43279D03*
Y53279D03*
Y63279D03*
Y78279D03*
Y88279D03*
Y98279D03*
Y108279D03*
Y118279D03*
Y128279D03*
Y73279D03*
Y83279D03*
Y93279D03*
Y103279D03*
Y113279D03*
Y123279D03*
Y133279D03*
Y138279D03*
Y148279D03*
Y158279D03*
Y168279D03*
Y178279D03*
Y188279D03*
Y198279D03*
Y143279D03*
Y153279D03*
Y163279D03*
Y173279D03*
Y183279D03*
Y193279D03*
Y208279D03*
Y218279D03*
Y228279D03*
Y238279D03*
Y248279D03*
Y258279D03*
Y203279D03*
Y213279D03*
Y223279D03*
Y233279D03*
Y243279D03*
Y253279D03*
Y263279D03*
Y268279D03*
Y278279D03*
Y288279D03*
Y298279D03*
Y308279D03*
Y318279D03*
Y328279D03*
Y273279D03*
Y283279D03*
Y293279D03*
Y303279D03*
Y313279D03*
Y323279D03*
Y338279D03*
Y348279D03*
Y358279D03*
Y368279D03*
Y378279D03*
Y388279D03*
Y333279D03*
Y343279D03*
Y353279D03*
Y363279D03*
Y373279D03*
Y383279D03*
Y393279D03*
Y398279D03*
Y408279D03*
Y418279D03*
Y428279D03*
Y438279D03*
Y448279D03*
Y458279D03*
Y403279D03*
Y413279D03*
Y423279D03*
Y433279D03*
Y443279D03*
Y453279D03*
Y468279D03*
Y478279D03*
Y488279D03*
Y498279D03*
Y508279D03*
Y518279D03*
Y528279D03*
Y463279D03*
Y473279D03*
Y483279D03*
Y493279D03*
Y503279D03*
Y513279D03*
Y523279D03*
Y538279D03*
Y548279D03*
Y558279D03*
Y568279D03*
Y578279D03*
Y588279D03*
Y533279D03*
Y543279D03*
Y553279D03*
Y563279D03*
Y573279D03*
Y583279D03*
Y593279D03*
Y598279D03*
Y608279D03*
Y618279D03*
Y628279D03*
Y638279D03*
Y648279D03*
Y658279D03*
Y603279D03*
Y613279D03*
Y623279D03*
Y633279D03*
Y643279D03*
Y653279D03*
Y668279D03*
Y678279D03*
Y688279D03*
Y698279D03*
Y708279D03*
Y718279D03*
Y663279D03*
Y673279D03*
Y683279D03*
Y693279D03*
Y703279D03*
Y713279D03*
X8892Y723187D03*
X11090Y727806D03*
X13500Y732400D03*
X78721Y8500D03*
X68721D03*
X58721D03*
X48721D03*
X38721D03*
X28721D03*
X18721D03*
X73721D03*
X53721D03*
X43721D03*
X33721D03*
X23721D03*
X63721D03*
X75534Y625175D03*
X75300Y679300D03*
Y674300D03*
X78370Y724300D03*
Y719500D03*
X28100Y755600D03*
X33100D03*
X69057Y755280D03*
X74057D03*
X20300Y746200D03*
X15800Y736900D03*
X18100Y741500D03*
X22600Y750800D03*
X79057Y755280D03*
X108721Y8500D03*
X98721D03*
X88721D03*
X112197Y65406D03*
Y60406D03*
Y55406D03*
X103721Y8500D03*
X93721D03*
X83721D03*
X112197Y75406D03*
Y85406D03*
Y95406D03*
Y105406D03*
Y115406D03*
Y120406D03*
Y110406D03*
Y100406D03*
Y90406D03*
Y80406D03*
Y70406D03*
Y145406D03*
Y195406D03*
Y185406D03*
Y175406D03*
Y165406D03*
Y155406D03*
Y200406D03*
Y190406D03*
Y180406D03*
Y170406D03*
Y160406D03*
Y150406D03*
Y265406D03*
Y255406D03*
Y245406D03*
Y235406D03*
Y225406D03*
Y215406D03*
Y205406D03*
Y260406D03*
Y250406D03*
Y240406D03*
Y230406D03*
Y220406D03*
Y210406D03*
Y325406D03*
Y315406D03*
Y305406D03*
Y295406D03*
Y285406D03*
Y275406D03*
Y330406D03*
Y320406D03*
Y310406D03*
Y300406D03*
Y290406D03*
Y280406D03*
Y270406D03*
Y390406D03*
Y380406D03*
Y370406D03*
Y360406D03*
Y350406D03*
Y395406D03*
Y385406D03*
Y375406D03*
Y365406D03*
Y355406D03*
Y345406D03*
Y335406D03*
Y340406D03*
Y420406D03*
Y410406D03*
Y400406D03*
Y425406D03*
Y415406D03*
Y405406D03*
X103600Y637800D03*
X103500Y645500D03*
Y650535D03*
X80334Y625175D03*
X99600Y673500D03*
Y678500D03*
X86500Y703100D03*
X86600Y708300D03*
X96800Y662000D03*
X90200Y667100D03*
X85400D03*
X99600Y683500D03*
X81300Y675100D03*
Y680100D03*
X134223Y691027D03*
X83170Y724300D03*
Y719500D03*
X122435Y666782D03*
Y661982D03*
X144057Y755280D03*
X134057D03*
X124057D03*
X114057D03*
X104057D03*
X94057D03*
X84057D03*
X89057D03*
X99057D03*
X109057D03*
X119057D03*
X129057D03*
X139057D03*
X91700Y744800D03*
X96500D03*
X101300D03*
X106100D03*
X110900D03*
X115700D03*
X120500D03*
X125300D03*
X208300Y704985D03*
X203500D03*
X198700D03*
X193900D03*
X155400Y717700D03*
X204057Y755280D03*
X194057D03*
X184057D03*
X174057D03*
X164057D03*
X154057D03*
X149057D03*
X159057D03*
X169057D03*
X179057D03*
X189057D03*
X199057D03*
X209057D03*
X222700Y704985D03*
X217900D03*
X213100D03*
X249500Y719500D03*
Y724300D03*
X274057Y755280D03*
X264057D03*
X254057D03*
X244057D03*
X234057D03*
X224057D03*
X214057D03*
X219057D03*
X229057D03*
X239057D03*
X249057D03*
X259057D03*
X269057D03*
X249500Y729100D03*
Y733900D03*
Y738700D03*
X315120Y8500D03*
X310120D03*
X305120D03*
X300120D03*
X296020Y9420D03*
Y14420D03*
Y19420D03*
Y24420D03*
Y29420D03*
X321382Y197574D03*
X296282Y189224D03*
Y184424D03*
X301082D03*
Y189224D03*
X335132Y195874D03*
X305862Y210014D03*
X334882Y215874D03*
Y220874D03*
X321382Y202374D03*
X335132Y205974D03*
X335200Y640100D03*
X330400D03*
X335000Y615400D03*
X335300Y609800D03*
X335000Y621200D03*
X325600Y640100D03*
X322586Y653754D03*
X317786D03*
X312986D03*
X308186D03*
X330200Y709300D03*
X334650Y689700D03*
X335350Y684650D03*
X315520Y711720D03*
X325700Y711600D03*
X320320Y711720D03*
X305500Y721000D03*
X310500D03*
X304150Y674700D03*
X299350D03*
X334057Y755280D03*
X324057D03*
X314057D03*
X304057D03*
X294057D03*
X284057D03*
X279057D03*
X289057D03*
X299057D03*
X309057D03*
X319057D03*
X329057D03*
X339057D03*
X305500Y726000D03*
X310500D03*
X381638Y755280D03*
X384809Y752321D03*
X387045Y747849D03*
X389281Y743376D03*
X391517Y738904D03*
X393753Y734432D03*
X395989Y729960D03*
X398225Y725488D03*
X344057Y755280D03*
X521634Y38901D03*
Y34101D03*
X516834Y38901D03*
Y34101D03*
X526434Y43701D03*
X521634D03*
X516834D03*
X520000Y63400D03*
X515200Y66440D03*
X520585Y68348D03*
X536794Y77373D03*
X531664Y78463D03*
X515915Y80576D03*
X520310Y76700D03*
X508668Y79607D03*
X503550Y79500D03*
X511100Y75060D03*
X506100D03*
X511100Y70060D03*
X525200Y71440D03*
X516628Y71806D03*
X600700Y35700D03*
X595500Y35600D03*
X595700Y29800D03*
X600900Y29700D03*
X576610Y388416D03*
Y393416D03*
X576512Y369625D03*
Y364825D03*
X581312Y369625D03*
Y364825D03*
X576610Y398416D03*
Y403416D03*
Y408416D03*
Y413416D03*
Y418416D03*
Y423416D03*
Y428416D03*
Y433416D03*
Y438416D03*
Y443416D03*
Y448416D03*
Y453416D03*
Y458416D03*
Y463416D03*
Y468416D03*
Y473416D03*
Y478416D03*
Y483416D03*
Y488416D03*
Y493416D03*
Y498416D03*
Y503416D03*
Y508416D03*
Y513416D03*
Y518416D03*
Y523416D03*
Y528416D03*
Y533416D03*
Y538416D03*
Y543416D03*
Y548416D03*
Y553416D03*
Y558416D03*
Y563416D03*
Y568416D03*
Y573416D03*
Y578416D03*
Y583416D03*
Y588416D03*
Y593416D03*
Y598416D03*
Y603416D03*
Y608416D03*
Y613416D03*
Y618416D03*
Y623416D03*
Y628416D03*
Y633416D03*
Y638416D03*
Y643416D03*
Y648416D03*
Y653416D03*
Y658416D03*
Y663416D03*
Y668416D03*
Y673416D03*
Y678416D03*
Y683416D03*
Y688416D03*
Y693416D03*
Y698416D03*
Y703416D03*
Y708416D03*
Y713416D03*
Y718416D03*
X577063Y723309D03*
X579299Y727781D03*
X581535Y732253D03*
X583771Y736725D03*
X586007Y741198D03*
X588243Y745670D03*
X590479Y750142D03*
X592715Y754614D03*
X609200Y330400D03*
X658000Y431500D03*
Y409000D03*
Y414000D03*
Y426000D03*
Y420500D03*
X642700Y454400D03*
X642500Y449100D03*
X642600Y459500D03*
X610000Y467500D03*
X609000Y473500D03*
Y478500D03*
Y483500D03*
X645200Y521900D03*
X650400Y517600D03*
X656400Y517500D03*
X661500Y517600D03*
X621600Y486619D03*
X626958Y486419D03*
X642500Y464700D03*
X629500Y482500D03*
Y477000D03*
Y471500D03*
X635000Y482500D03*
Y476500D03*
Y471000D03*
X615500Y529800D03*
X616710Y534500D03*
X657000Y555000D03*
X662000D03*
X661887Y560010D03*
X656887D03*
X645300Y655200D03*
Y650400D03*
Y645600D03*
Y640800D03*
X655000Y705000D03*
Y700200D03*
Y695400D03*
Y690600D03*
X645300Y684000D03*
Y679200D03*
Y674400D03*
Y669600D03*
Y664800D03*
Y660000D03*
X655000Y685800D03*
X659722Y755280D03*
X649722D03*
X639722D03*
X634722D03*
X644722D03*
X654722D03*
X664722D03*
X708483Y311988D03*
X713283D03*
X723900Y326350D03*
X718940Y326270D03*
X714900Y453600D03*
X715200Y459600D03*
X706700Y413900D03*
X710200Y417400D03*
Y422900D03*
Y427900D03*
X698700Y417600D03*
Y423100D03*
Y428100D03*
X676000Y431000D03*
X671000D03*
Y421000D03*
X676000D03*
X671000Y426000D03*
X676000D03*
X715200Y465000D03*
X689500Y518500D03*
Y524000D03*
X694738Y523940D03*
X694690Y519034D03*
X670400Y565500D03*
Y560700D03*
Y555900D03*
Y551100D03*
Y546300D03*
Y541500D03*
Y536700D03*
X687015Y658100D03*
Y653300D03*
Y648500D03*
Y643700D03*
Y682100D03*
X673950Y686104D03*
Y691104D03*
Y696104D03*
Y701104D03*
Y706104D03*
X687015Y677300D03*
Y672500D03*
Y667700D03*
Y662900D03*
X729722Y755280D03*
X719722D03*
X709722D03*
X699722D03*
X689722D03*
X679722D03*
X669722D03*
X674722D03*
X684722D03*
X694722D03*
X704722D03*
X714722D03*
X724722D03*
X734722D03*
X780100Y8500D03*
X775100D03*
X770100D03*
X765100D03*
X760100D03*
X755100D03*
X750100D03*
X745100D03*
X787895D03*
X797895D03*
X792895D03*
X754000Y172700D03*
Y177500D03*
X798359Y351659D03*
X795193Y355540D03*
X791786Y359001D03*
X735484Y429378D03*
Y434178D03*
Y462978D03*
Y458178D03*
Y453378D03*
Y448578D03*
Y443778D03*
Y438978D03*
X798000Y459300D03*
X740300Y427100D03*
Y431900D03*
X751100Y405400D03*
X755900D03*
X760700D03*
X765500D03*
X770300D03*
X775100D03*
X740300Y446300D03*
Y441500D03*
Y436700D03*
X790600Y458000D03*
X781000D03*
X785800D03*
X776200D03*
X789500Y405400D03*
X784700D03*
X779900D03*
X750000Y427100D03*
X754800D03*
X783800Y436000D03*
X779000D03*
X793400D03*
X788600D03*
X788400Y427100D03*
X783600D03*
X778800D03*
X774200Y436000D03*
X774000Y427100D03*
X769200D03*
X764400D03*
X759600D03*
X735484Y467778D03*
X799722Y755280D03*
X789722D03*
X779722D03*
X769722D03*
X759722D03*
X749722D03*
X739722D03*
X744722D03*
X754722D03*
X764722D03*
X774722D03*
X784722D03*
X794722D03*
X807895Y8500D03*
X817895D03*
X827895D03*
X837895D03*
X847895D03*
X857895D03*
X862895D03*
X852895D03*
X842895D03*
X832895D03*
X822895D03*
X812895D03*
X802895D03*
X842600Y339400D03*
X841100Y332300D03*
X826993Y358840D03*
X821502Y358356D03*
X827145Y363638D03*
X821653Y363488D03*
X826900Y332500D03*
X825300Y339900D03*
X825100Y347300D03*
X828100Y352900D03*
X809792Y379122D03*
X814592D03*
X809792Y374322D03*
X814592D03*
X842900Y347200D03*
X840800Y352800D03*
X828000Y459300D03*
X823200D03*
X832800D03*
X818400D03*
X807600D03*
X802800D03*
X812400D03*
X864727Y398458D03*
X804300Y436500D03*
X813900D03*
X809100D03*
X818700D03*
X823500D03*
X830100Y501500D03*
X839700D03*
X834900D03*
X827000Y516000D03*
X832000D03*
Y521000D03*
X827000D03*
X843900Y464000D03*
X848700Y465200D03*
Y470600D03*
X849722Y755280D03*
X839722D03*
X829722D03*
X819722D03*
X809722D03*
X804722D03*
X814722D03*
X824722D03*
X834722D03*
X844722D03*
X854722D03*
X867895Y8500D03*
X877895D03*
X887895D03*
X897895D03*
X907895D03*
X916697Y19698D03*
Y29698D03*
Y39698D03*
Y49698D03*
Y59698D03*
Y69698D03*
Y64698D03*
Y54698D03*
Y44698D03*
Y34698D03*
Y24698D03*
Y14698D03*
X912895Y8500D03*
X902895D03*
X892895D03*
X882895D03*
X872895D03*
X916697Y79698D03*
Y89698D03*
Y99698D03*
Y109698D03*
Y119698D03*
Y129698D03*
Y134698D03*
Y124698D03*
Y114698D03*
Y104698D03*
Y94698D03*
Y84698D03*
Y74698D03*
Y139698D03*
Y149698D03*
Y159698D03*
Y169698D03*
Y179698D03*
Y189698D03*
Y199698D03*
Y194698D03*
Y184698D03*
Y174698D03*
Y164698D03*
Y154698D03*
Y144698D03*
Y209698D03*
Y219698D03*
Y229698D03*
Y239698D03*
Y249698D03*
Y259698D03*
Y264698D03*
Y254698D03*
Y244698D03*
Y234698D03*
Y224698D03*
Y214698D03*
Y204698D03*
Y269698D03*
Y279698D03*
Y289698D03*
Y299698D03*
Y309698D03*
Y319698D03*
Y329698D03*
Y324698D03*
Y314698D03*
Y304698D03*
Y294698D03*
Y284698D03*
Y274698D03*
Y339698D03*
Y349698D03*
Y359698D03*
Y369698D03*
Y379698D03*
Y389698D03*
Y394698D03*
Y384698D03*
Y374698D03*
Y364698D03*
Y354698D03*
Y344698D03*
Y334698D03*
X881147Y394517D03*
X916697Y399698D03*
Y409698D03*
Y419698D03*
Y429698D03*
Y439698D03*
Y449698D03*
Y459698D03*
Y454698D03*
Y444698D03*
Y434698D03*
Y424698D03*
Y414698D03*
Y404698D03*
X874727Y398458D03*
X869727D03*
X880887Y399474D03*
X916697Y469698D03*
Y479698D03*
Y489698D03*
Y499698D03*
Y509698D03*
Y519698D03*
Y524698D03*
Y514698D03*
Y504698D03*
Y494698D03*
Y484698D03*
Y474698D03*
Y464698D03*
Y529698D03*
Y539698D03*
Y549698D03*
Y559698D03*
Y569698D03*
Y579698D03*
Y589698D03*
Y584698D03*
Y574698D03*
Y564698D03*
Y554698D03*
Y544698D03*
Y534698D03*
Y599698D03*
Y609698D03*
Y619698D03*
Y629698D03*
Y639698D03*
Y649698D03*
Y659698D03*
Y654698D03*
Y644698D03*
Y634698D03*
Y624698D03*
Y614698D03*
Y604698D03*
Y594698D03*
Y669698D03*
Y679698D03*
Y689698D03*
Y699698D03*
Y709698D03*
Y719698D03*
Y714698D03*
Y704698D03*
Y694698D03*
Y684698D03*
Y674698D03*
Y664698D03*
X914700Y726100D03*
X912436Y730603D03*
X910200Y735300D03*
X907564Y739747D03*
X905500Y744400D03*
X903192Y748791D03*
X900800Y753700D03*
X894722Y755280D03*
G54D131*
X653700Y653200D03*
Y673400D03*
X678500Y653200D03*
Y673400D03*
G54D20*
X50960Y58330D03*
Y47330D03*
X71090Y63300D03*
Y52300D03*
X632460Y164580D03*
Y153580D03*
X659200Y538200D03*
Y549200D03*
X758435Y410973D03*
Y421973D03*
X767135Y410973D03*
Y421973D03*
X775835Y410973D03*
Y421973D03*
X790300Y452400D03*
Y441400D03*
X749700Y411000D03*
Y422000D03*
X781400Y452400D03*
Y441400D03*
X864928Y382092D03*
Y393092D03*
X873623Y382038D03*
Y393038D03*
G54D104*
X458250Y30479D03*
Y32447D03*
Y34416D03*
Y36384D03*
Y38353D03*
Y40321D03*
X477750D03*
Y38353D03*
Y36384D03*
Y34416D03*
Y32447D03*
Y30479D03*
G54D140*
X752180Y485279D03*
Y483311D03*
Y481342D03*
Y479374D03*
X735464Y485279D03*
Y481342D03*
Y483311D03*
G54D11*
X80708Y44292D03*
X61024Y34449D03*
X33464D03*
X56102Y24606D03*
X38386D03*
X108268Y44292D03*
X103346Y34449D03*
X85630D03*
X590300Y574400D03*
X600300D03*
X610300D03*
G54D113*
X564803Y24409D03*
X574803D03*
X584803D03*
X753780D03*
X763780D03*
X773780D03*
X801024D03*
X811024D03*
X821024D03*
G54D122*
X615750Y463000D03*
X616250D03*
G54D12*
X38780Y48060D03*
X76100Y690300D03*
X89034Y55935D03*
X110220Y481998D03*
X142100Y519900D03*
X105920Y489718D03*
X110220Y489678D03*
X108600Y570550D03*
X123900Y648000D03*
X127900D03*
X140700Y650100D03*
X111200Y709900D03*
X80600Y685500D03*
X203500Y516900D03*
X199500Y517000D03*
X184167Y502984D03*
X183277Y485678D03*
X178920D03*
X151900Y633900D03*
X147800D03*
X168900Y633600D03*
X149400Y622800D03*
X193285Y621100D03*
X189185D03*
X185085D03*
X181085D03*
X177000Y620000D03*
X172900D03*
X164800Y633600D03*
X197555Y633257D03*
X200850Y643000D03*
X145300Y622800D03*
X208516Y653501D03*
X196648Y653621D03*
X161000Y644300D03*
X144800Y650100D03*
X164349Y695415D03*
X151749Y695715D03*
X166400Y704800D03*
X154300Y703515D03*
X216900Y512266D03*
X212600Y517000D03*
X225600Y515380D03*
X269600Y528100D03*
X252272Y613181D03*
X225900Y623700D03*
X229900Y625000D03*
X221900Y623700D03*
X238000Y622800D03*
X234000D03*
X223400Y638000D03*
X244156Y613787D03*
X242900Y675700D03*
X258431Y704490D03*
X249842Y707310D03*
X339851Y179517D03*
X340942Y528526D03*
X314181Y586050D03*
X297175Y535054D03*
X305100Y658100D03*
X289800Y660500D03*
X328000Y669900D03*
X291700Y730200D03*
X287620Y730220D03*
X370682Y192874D03*
X350000Y521000D03*
X354440Y485830D03*
X356680Y585664D03*
X374292Y583400D03*
X350000Y529000D03*
X385600Y532500D03*
X345900Y578100D03*
X392133Y594490D03*
X468200Y62600D03*
X463200Y55700D03*
X444754Y42401D03*
X472500Y62500D03*
X639067Y358591D03*
X613223Y372527D03*
X637147Y396797D03*
X646469Y417486D03*
X632628Y554627D03*
X727150Y187850D03*
X722150D03*
X725678Y176992D03*
X711150Y177600D03*
X716650Y187850D03*
X705650D03*
X711150D03*
X714090Y324840D03*
X706000Y324800D03*
X727200Y356100D03*
X722500Y346300D03*
X713500Y356200D03*
X718000Y346300D03*
X689000Y499800D03*
X713575Y552777D03*
X728000Y580250D03*
X703800Y601500D03*
X784161Y123415D03*
X784400Y99300D03*
X741300Y188800D03*
X758100Y188400D03*
X754000Y188800D03*
X738365Y356035D03*
X790400Y416400D03*
X795922Y522908D03*
X777200Y496800D03*
X759200Y500800D03*
X753099Y523066D03*
X748899Y522966D03*
X818688Y403255D03*
X857000Y403400D03*
X805249Y519877D03*
X885568Y318641D03*
G54D30*
X61284Y643900D03*
X143049Y740015D03*
X145100Y691600D03*
X200686Y698355D03*
X272000Y715100D03*
X294800Y524750D03*
X299319Y553653D03*
X290700Y543000D03*
X302070Y612350D03*
X281860Y644250D03*
X291204Y688120D03*
X377200Y543200D03*
X358986Y639880D03*
X350230Y702620D03*
X442535Y34357D03*
X626722Y368128D03*
X610110Y521543D03*
X616700Y467000D03*
X621860Y554943D03*
X639300Y557500D03*
X741030Y452700D03*
X814434Y389702D03*
X805900Y477200D03*
G54D123*
X625100Y494326D03*
Y510074D03*
G54D21*
X70865Y98425D03*
Y472440D03*
X49213Y740157D03*
X314960Y472440D03*
X405511Y39370D03*
X364173Y740157D03*
X612204Y433070D03*
Y740157D03*
X875985Y59055D03*
X875984Y433070D03*
Y740157D03*
G54D132*
X720039Y422909D03*
X704539D03*
G54D105*
X468000Y35400D03*
G54D114*
X576160Y54765D03*
X573600D03*
X571040D03*
Y62835D03*
X573600D03*
X576160D03*
X765260Y50010D03*
X762700D03*
X760140D03*
Y58080D03*
X762700D03*
X765260D03*
G54D141*
X750712Y488716D03*
X748743D03*
X738901D03*
X736932D03*
X740869D03*
X742838D03*
X744806D03*
X746775D03*
G54D13*
X38780Y51460D03*
X76100Y693700D03*
X89034Y59335D03*
X110220Y485398D03*
X142100Y523300D03*
X105920Y493118D03*
X110220Y493078D03*
X108600Y573950D03*
X123900Y651400D03*
X127900D03*
X140700Y653500D03*
X111200Y713300D03*
X80600Y688900D03*
X203500Y520300D03*
X199500Y520400D03*
X184167Y506384D03*
X183277Y489078D03*
X178920D03*
X151900Y637300D03*
X147800D03*
X168900Y637000D03*
X149400Y626200D03*
X193285Y624500D03*
X189185D03*
X185085D03*
X181085D03*
X177000Y623400D03*
X172900D03*
X164800Y637000D03*
X197555Y636657D03*
X200850Y646400D03*
X145300Y626200D03*
X208516Y656901D03*
X196648Y657021D03*
X161000Y647700D03*
X144800Y653500D03*
X164349Y698815D03*
X151749Y699115D03*
X166400Y708200D03*
X154300Y706915D03*
X216900Y515666D03*
X212600Y520400D03*
X225600Y518780D03*
X269600Y531500D03*
X252272Y616581D03*
X225900Y627100D03*
X229900Y628400D03*
X221900Y627100D03*
X238000Y626200D03*
X234000D03*
X223400Y641400D03*
X244156Y617187D03*
X242900Y679100D03*
X258431Y707890D03*
X249842Y710710D03*
X339851Y182917D03*
X340942Y531926D03*
X314181Y589450D03*
X297175Y538454D03*
X305100Y661500D03*
X289800Y663900D03*
X328000Y673300D03*
X291700Y733600D03*
X287620Y733620D03*
X370682Y196274D03*
X350000Y524400D03*
X354440Y489230D03*
X356680Y589064D03*
X374292Y586800D03*
X350000Y532400D03*
X385600Y535900D03*
X345900Y581500D03*
X392133Y597890D03*
X468200Y66000D03*
X463200Y59100D03*
X444754Y45801D03*
X472500Y65900D03*
X639067Y361991D03*
X613223Y375927D03*
X646469Y420886D03*
X637147Y400197D03*
X632628Y558027D03*
X727150Y191250D03*
X722150D03*
X725678Y180392D03*
X711150Y181000D03*
X716650Y191250D03*
X705650D03*
X711150D03*
X714090Y328240D03*
X706000Y328200D03*
X727200Y359500D03*
X722500Y349700D03*
X713500Y359600D03*
X718000Y349700D03*
X689000Y503200D03*
X713575Y556177D03*
X728000Y583650D03*
X703800Y604900D03*
X784161Y126815D03*
X784400Y102700D03*
X741300Y192200D03*
X758100Y191800D03*
X754000Y192200D03*
X738365Y359435D03*
X790400Y419800D03*
X795922Y526308D03*
X777200Y500200D03*
X759200Y504200D03*
X753099Y526466D03*
X748899Y526366D03*
X818688Y406655D03*
X857000Y406800D03*
X805249Y523277D03*
X885568Y322041D03*
G54D115*
X599998Y386961D03*
X589873Y379461D03*
X593748Y386961D03*
X585998D03*
X603873Y379461D03*
X607748Y386961D03*
X767684Y524500D03*
X786584Y525000D03*
X771559Y532000D03*
X763809D03*
X790459Y532500D03*
X782709D03*
G54D31*
X77766Y637546D03*
Y629946D03*
X83750Y654654D03*
X91550Y654554D03*
X83750Y662254D03*
X91550Y662154D03*
X101749Y730715D03*
Y738315D03*
X94020Y730691D03*
Y738291D03*
X124820Y732391D03*
Y739991D03*
X109449Y730715D03*
Y738315D03*
X117149Y730715D03*
Y738315D03*
X132651Y732415D03*
Y740015D03*
X219600Y717700D03*
Y710100D03*
X211800Y717700D03*
Y710100D03*
X324636Y627604D03*
Y635204D03*
X332436Y627504D03*
Y635104D03*
X319536Y658504D03*
X311636D03*
X311936Y609096D03*
Y601496D03*
X321470Y698774D03*
Y706374D03*
X313670Y698874D03*
Y706474D03*
X319536Y666104D03*
X311636D03*
X309300Y683100D03*
Y675500D03*
X298470Y731174D03*
Y738774D03*
X306370Y731174D03*
Y738774D03*
X659600Y523200D03*
X651500D03*
X659600Y530800D03*
X651500D03*
X692000Y529500D03*
Y537100D03*
X742700Y457680D03*
Y465280D03*
X821050Y519654D03*
Y527254D03*
X813150Y519654D03*
Y527254D03*
X828250Y488954D03*
Y496554D03*
X836050Y488854D03*
Y496454D03*
G54D22*
X89764Y238386D03*
X309252Y413583D03*
G54D40*
X125481Y460299D03*
Y465299D03*
Y470299D03*
Y475299D03*
Y480299D03*
Y485299D03*
Y490299D03*
Y495299D03*
X164039Y460299D03*
Y495299D03*
Y490299D03*
Y485299D03*
Y480299D03*
Y475299D03*
Y470299D03*
Y465299D03*
X220521Y460300D03*
X259079D03*
X220521Y465300D03*
Y470300D03*
Y475300D03*
Y480300D03*
Y485300D03*
Y490300D03*
Y495300D03*
X259079D03*
Y490300D03*
Y485300D03*
Y480300D03*
Y475300D03*
Y470300D03*
Y465300D03*
G54D142*
X815076Y55812D03*
Y53252D03*
Y50692D03*
X807006D03*
Y53252D03*
Y55812D03*
G54D133*
X700546Y577599D03*
G54D124*
X617250Y555400D03*
X721150Y576300D03*
G54D106*
X421653Y126378D03*
X435827D03*
X450000D03*
X464173D03*
X428740Y121654D03*
X442913D03*
X457086D03*
X471260D03*
X421653Y130709D03*
X428740Y125985D03*
X435827Y130709D03*
X442913Y125985D03*
X450000Y130709D03*
X457086Y125985D03*
X464173Y130709D03*
X471260Y125985D03*
X428740Y131496D03*
X442913D03*
X457086D03*
X471260D03*
X421653Y183071D03*
X435827D03*
X450000D03*
X464173D03*
X421653Y136221D03*
X435827D03*
X450000D03*
X464173D03*
X421653Y140551D03*
X428740Y135827D03*
X435827Y140551D03*
X442913Y135827D03*
X450000Y140551D03*
X457086Y135827D03*
X464173Y140551D03*
X471260Y135827D03*
X421653Y144882D03*
X428740Y140158D03*
X435827Y144882D03*
X442913Y140158D03*
X450000Y144882D03*
X457086Y140158D03*
X464173Y144882D03*
X471260Y140158D03*
X421653Y150394D03*
X428740Y145670D03*
X435827Y150394D03*
X442913Y145670D03*
X450000Y150394D03*
X457086Y145670D03*
X464173Y150394D03*
X471260Y145670D03*
X421653Y154725D03*
X428740Y150000D03*
X435827Y154725D03*
X442913Y150000D03*
X450000Y154725D03*
X457086Y150000D03*
X464173Y154725D03*
X471260Y150000D03*
X421653Y159055D03*
X428740Y154331D03*
X435827Y159055D03*
X442913Y154331D03*
X450000Y159055D03*
X457086Y154331D03*
X464173Y159055D03*
X471260Y154331D03*
X421653Y164567D03*
X428740Y159843D03*
X435827Y164567D03*
X442913Y159843D03*
X450000Y164567D03*
X457086Y159843D03*
X464173Y164567D03*
X471260Y159843D03*
X421653Y168898D03*
X428740Y164173D03*
X435827Y168898D03*
X442913Y164173D03*
X450000Y168898D03*
X457086Y164173D03*
X464173Y168898D03*
X471260Y164173D03*
X421653Y173229D03*
X428740Y168504D03*
X435827Y173229D03*
X442913Y168504D03*
X450000Y173229D03*
X457086Y168504D03*
X464173Y173229D03*
X471260Y168504D03*
X421653Y178740D03*
X428740Y174016D03*
X435827Y178740D03*
X442913Y174016D03*
X450000Y178740D03*
X457086Y174016D03*
X464173Y178740D03*
X471260Y174016D03*
X506693Y126378D03*
X520866D03*
X535039D03*
X513779Y121654D03*
X527953D03*
X506693Y130709D03*
X513779Y125985D03*
X520866Y130709D03*
X527953Y125985D03*
X535039Y130709D03*
X513779Y131496D03*
X527953D03*
X506693Y183071D03*
X520866D03*
X535039D03*
X506693Y136221D03*
X520866D03*
X535039D03*
X506693Y140551D03*
X513779Y135827D03*
X520866Y140551D03*
X527953Y135827D03*
X535039Y140551D03*
X506693Y144882D03*
X513779Y140158D03*
X520866Y144882D03*
X527953Y140158D03*
X535039Y144882D03*
X506693Y150394D03*
X513779Y145670D03*
X520866Y150394D03*
X527953Y145670D03*
X535039Y150394D03*
X506693Y154725D03*
X513779Y150000D03*
X520866Y154725D03*
X527953Y150000D03*
X535039Y154725D03*
X506693Y159055D03*
X513779Y154331D03*
X520866Y159055D03*
X527953Y154331D03*
X535039Y159055D03*
X506693Y164567D03*
X513779Y159843D03*
X520866Y164567D03*
X527953Y159843D03*
X535039Y164567D03*
X506693Y168898D03*
X513779Y164173D03*
X520866Y168898D03*
X527953Y164173D03*
X535039Y168898D03*
X506693Y173229D03*
X513779Y168504D03*
X520866Y173229D03*
X527953Y168504D03*
X535039Y173229D03*
X506693Y178740D03*
X513779Y174016D03*
X520866Y178740D03*
X527953Y174016D03*
X535039Y178740D03*
X549212Y126378D03*
X542126Y121654D03*
X556299D03*
X542126Y125985D03*
X549212Y130709D03*
X556299Y125985D03*
X542126Y131496D03*
X556299D03*
X549212Y183071D03*
Y136221D03*
X542126Y135827D03*
X549212Y140551D03*
X556299Y135827D03*
X542126Y140158D03*
X549212Y144882D03*
X556299Y140158D03*
X542126Y145670D03*
X549212Y150394D03*
X556299Y145670D03*
X542126Y150000D03*
X549212Y154725D03*
X556299Y150000D03*
X542126Y154331D03*
X549212Y159055D03*
X556299Y154331D03*
X542126Y159843D03*
X549212Y164567D03*
X556299Y159843D03*
X542126Y164173D03*
X549212Y168898D03*
X556299Y164173D03*
X542126Y168504D03*
X549212Y173229D03*
X556299Y168504D03*
X542126Y174016D03*
X549212Y178740D03*
X556299Y174016D03*
G54D125*
X614750Y555400D03*
X718650Y576300D03*
G54D23*
X44206Y543876D03*
X36758Y543881D03*
X44187Y555153D03*
X36687D03*
X44000Y549500D03*
X36500D03*
X44206Y538249D03*
X36658Y538254D03*
X44106Y532622D03*
X64746Y647850D03*
X130400Y534600D03*
X140300Y529700D03*
X140424Y538335D03*
X130400Y530300D03*
X123403Y609818D03*
X126397Y601923D03*
X126100Y632300D03*
Y636400D03*
X200800Y502800D03*
X182920Y473998D03*
X156800Y648400D03*
X148549Y683715D03*
X158549Y711215D03*
X212100Y495300D03*
X271300Y474500D03*
X251466Y567108D03*
X251100Y573500D03*
X250850Y578300D03*
X243700Y588900D03*
X243010Y537139D03*
X251100Y585700D03*
X242970Y552558D03*
X264200Y539500D03*
X267600Y552100D03*
X243996Y560698D03*
Y564798D03*
X258274Y552061D03*
X251396Y556761D03*
X251477Y563068D03*
X228016Y658967D03*
X238200Y633200D03*
X243300Y601000D03*
X263273Y634343D03*
X275420Y718920D03*
X238900Y659100D03*
X261719Y662209D03*
X302432Y578108D03*
X277700Y575000D03*
X296800Y573700D03*
X297500Y569700D03*
X295100Y565600D03*
X302600Y564200D03*
X302876Y557611D03*
X316033Y535357D03*
X305448Y620477D03*
X285360Y647950D03*
Y652100D03*
X294782Y691947D03*
X345629Y193678D03*
X370372Y245284D03*
X343617Y231156D03*
X343659Y261112D03*
X370242Y224934D03*
X370472Y240684D03*
X345378Y517086D03*
X351261Y507831D03*
X358030Y481570D03*
X348700Y545100D03*
X389700Y568500D03*
X391181Y623786D03*
X391100Y610300D03*
X366064Y635920D03*
X490000Y49100D03*
X493200Y34000D03*
X485800Y67973D03*
X485925Y58850D03*
X596900Y373300D03*
X607708Y373437D03*
X633722Y375305D03*
X649800Y504100D03*
X642860Y549543D03*
X699920Y197740D03*
X688500Y255400D03*
X700000Y244800D03*
X685400Y249100D03*
X697300Y228400D03*
Y232400D03*
Y236850D03*
X684847Y240430D03*
X689000Y265100D03*
X688600Y259500D03*
X699403Y211743D03*
X699550Y203560D03*
X688947Y277530D03*
Y269230D03*
X688800Y285900D03*
X688947Y281730D03*
X686200Y307000D03*
X688947Y273430D03*
X674550Y470684D03*
X675900Y503900D03*
X699400Y504000D03*
X706538Y553602D03*
X722000Y569100D03*
X711200Y614500D03*
X719576Y594029D03*
X757720Y126510D03*
X785954Y514350D03*
X788684Y505600D03*
X780700Y518500D03*
X771019Y488799D03*
X747200Y508600D03*
X823200Y322500D03*
X809334Y480900D03*
X868950Y403400D03*
G54D41*
X126185Y460299D03*
Y495299D03*
Y490299D03*
Y485299D03*
Y480299D03*
Y475299D03*
Y470299D03*
Y465299D03*
X163335Y460299D03*
Y465299D03*
Y470299D03*
Y475299D03*
Y480299D03*
Y485299D03*
Y490299D03*
Y495299D03*
X258375Y460300D03*
X221225D03*
X258375Y465300D03*
Y470300D03*
Y475300D03*
Y480300D03*
Y485300D03*
Y490300D03*
Y495300D03*
X221225D03*
Y490300D03*
Y485300D03*
Y480300D03*
Y475300D03*
Y470300D03*
Y465300D03*
X267600Y582000D03*
Y587000D03*
Y592000D03*
Y597000D03*
X287600Y592000D03*
Y587000D03*
Y582000D03*
Y597000D03*
X379088Y526681D03*
Y521681D03*
X359088D03*
Y526681D03*
X379088Y536681D03*
Y531681D03*
X359088D03*
Y536681D03*
X648546Y449321D03*
Y454321D03*
Y459321D03*
X668546D03*
Y454321D03*
Y449321D03*
X648546Y464321D03*
X668546D03*
X830300Y388800D03*
Y393800D03*
X850300D03*
Y388800D03*
X830300Y398800D03*
Y403800D03*
X850300D03*
Y398800D03*
G54D116*
X629921Y57874D03*
X708661D03*
G54D107*
X535048Y54803D03*
Y48397D03*
G54D134*
X710389Y567956D03*
X708420D03*
X706452D03*
X704483D03*
X702515D03*
X700546D03*
X698577D03*
X696609D03*
X694640D03*
X692672D03*
X690703D03*
Y587242D03*
X692672D03*
X694640D03*
X696609D03*
X698577D03*
X700546D03*
X702515D03*
X704483D03*
X706452D03*
X708420D03*
X710389D03*
G54D32*
X70832Y656107D03*
X68273D03*
X65714D03*
X63155D03*
X60596D03*
Y675593D03*
X63155D03*
X65714D03*
X68273D03*
X70832D03*
X311418Y628857D03*
X308859D03*
X306300D03*
X303741D03*
X301182D03*
Y648343D03*
X303741D03*
X306300D03*
X308859D03*
X311418D03*
X300752Y700327D03*
X298193D03*
X295634D03*
X293075D03*
X290516D03*
Y719813D03*
X293075D03*
X295634D03*
X298193D03*
X300752D03*
X815332Y490107D03*
X812773D03*
X810214D03*
X807655D03*
X805096D03*
Y509593D03*
X807655D03*
X810214D03*
X812773D03*
X815332D03*
G54D50*
X125376Y705002D03*
Y706971D03*
Y708939D03*
Y710908D03*
Y712876D03*
Y714845D03*
Y716814D03*
Y718782D03*
Y720751D03*
Y722719D03*
X144662D03*
Y720751D03*
Y718782D03*
Y716814D03*
Y714845D03*
Y712876D03*
Y710908D03*
Y708939D03*
Y706971D03*
Y705002D03*
X125376Y724688D03*
X144662D03*
G54D14*
X58010Y52510D03*
X75373Y509879D03*
X75405Y517477D03*
X69900Y510000D03*
X69778Y517477D03*
X46100Y674984D03*
X79570Y58460D03*
X81032Y517477D03*
X81068Y509866D03*
X105920Y485398D03*
X86659Y517477D03*
X86673Y510000D03*
X92000Y517400D03*
X101100Y515300D03*
X101113Y522777D03*
X142000Y515500D03*
X93531Y496341D03*
X132100Y651400D03*
X136100D03*
X113349Y697047D03*
X117449D03*
X121549Y694747D03*
X193000Y506400D03*
X146112Y516498D03*
X183320Y481498D03*
X178920D03*
X174715Y520420D03*
X187000Y520400D03*
X191100Y519900D03*
X170700Y520400D03*
X166600D03*
X178869Y520393D03*
X182874Y520391D03*
X160727Y520222D03*
X150112Y516498D03*
X156721Y520192D03*
X188400Y506300D03*
X185276Y636268D03*
X177100Y637000D03*
X173000D03*
X202560Y627466D03*
X197315Y625797D03*
X153700Y626200D03*
X189376Y636268D03*
X193476D03*
X181146Y637008D03*
X188400Y647400D03*
X149300Y648400D03*
X204357Y656886D03*
X191746Y657042D03*
X165000Y647700D03*
X155849Y699115D03*
X158349Y706915D03*
X230262Y518680D03*
X234348Y518614D03*
X238648D03*
X242700Y518620D03*
X243400Y642900D03*
X248215Y616587D03*
X219200Y644000D03*
X231300Y645500D03*
X211706Y641392D03*
X251900Y679700D03*
X238936Y666869D03*
X258500Y679200D03*
X266800Y671000D03*
X262645Y707901D03*
X270900Y674000D03*
X293150Y538700D03*
X289050D03*
X300200Y593600D03*
X304300D03*
X336500Y673500D03*
X391262Y72271D03*
X386027Y72240D03*
X362484Y200119D03*
X349004Y183030D03*
X363553Y479662D03*
X382550Y584806D03*
X360820Y590236D03*
X352480Y589564D03*
X378350Y584806D03*
X345287Y540959D03*
X391549Y563600D03*
X387733Y597990D03*
X348600Y639000D03*
X444722Y53415D03*
X603164Y544203D03*
X639040Y161110D03*
X634661Y370756D03*
X620822Y375864D03*
X623239Y340879D03*
X608500Y339400D03*
X640160Y525243D03*
X619400Y567200D03*
X623542Y567152D03*
X732000Y192400D03*
X734028Y182346D03*
X716650Y181000D03*
X710060Y328260D03*
X727000Y349700D03*
X731400Y359400D03*
X711700Y348700D03*
X696527Y460706D03*
X696700Y473300D03*
X702390Y492260D03*
X731676Y591129D03*
X707826Y604879D03*
X716345Y611790D03*
X777700Y77600D03*
X795600Y191800D03*
X790600D03*
X762200Y192200D03*
X745700Y192400D03*
X737000D03*
X775500Y191700D03*
X749900Y192100D03*
X785600Y191800D03*
X738465Y349635D03*
X777000Y492500D03*
X751400Y504200D03*
X777084Y526450D03*
X841300Y61280D03*
X809349Y70036D03*
X813449D03*
X805600Y191800D03*
X800600D03*
X810600D03*
X857569Y388333D03*
X861000Y406800D03*
X882913Y232198D03*
G54D143*
X818018Y260200D03*
X820218D03*
X818018Y262400D03*
X820218D03*
X818018Y255800D03*
X820218D03*
X818018Y253600D03*
X820218D03*
X818018Y266800D03*
X820218D03*
X818018Y269000D03*
X820218D03*
X818018Y273400D03*
X820218D03*
X818018Y275600D03*
X820218D03*
X818018Y280000D03*
X820218D03*
X818018Y282200D03*
X820218D03*
X818018Y286600D03*
X820218D03*
X818018Y288800D03*
X820218D03*
X818018Y293200D03*
X820218D03*
X818018Y295400D03*
X820218D03*
X818018Y299800D03*
X820218D03*
X818018Y302000D03*
X820218D03*
G54D24*
X40806Y543876D03*
X33358Y543881D03*
X40787Y555153D03*
X33287D03*
X40600Y549500D03*
X33100D03*
X40806Y538249D03*
X33258Y538254D03*
X40706Y532622D03*
X61346Y647850D03*
X127000Y534600D03*
X136900Y529700D03*
X137024Y538335D03*
X127000Y530300D03*
X120003Y609818D03*
X122997Y601923D03*
X122700Y632300D03*
Y636400D03*
X208700Y495300D03*
X197400Y502800D03*
X179520Y473998D03*
X153400Y648400D03*
X145149Y683715D03*
X155149Y711215D03*
X267900Y474500D03*
X248066Y567108D03*
X247700Y573500D03*
X247450Y578300D03*
X240300Y588900D03*
X239610Y537139D03*
X247700Y585700D03*
X239570Y552558D03*
X260800Y539500D03*
X264200Y552100D03*
X240596Y560698D03*
Y564798D03*
X254874Y552061D03*
X247996Y556761D03*
X248077Y563068D03*
X274300Y575000D03*
X224616Y658967D03*
X234800Y633200D03*
X239900Y601000D03*
X259873Y634343D03*
X272020Y718920D03*
X235500Y659100D03*
X258319Y662209D03*
X340217Y231156D03*
X340259Y261112D03*
X299032Y578108D03*
X293400Y573700D03*
X294100Y569700D03*
X291700Y565600D03*
X299200Y564200D03*
X299476Y557611D03*
X312633Y535357D03*
X302048Y620477D03*
X281960Y647950D03*
Y652100D03*
X291382Y691947D03*
X342229Y193678D03*
X366972Y245284D03*
X366842Y224934D03*
X367072Y240684D03*
X341978Y517086D03*
X347861Y507831D03*
X354630Y481570D03*
X345300Y545100D03*
X386300Y568500D03*
X387781Y623786D03*
X387700Y610300D03*
X362664Y635920D03*
X486600Y49100D03*
X489800Y34000D03*
X482400Y67973D03*
X482525Y58850D03*
X593500Y373300D03*
X604308Y373437D03*
X630322Y375305D03*
X646400Y504100D03*
X639460Y549543D03*
X696520Y197740D03*
X685100Y255400D03*
X696600Y244800D03*
X682000Y249100D03*
X693900Y228400D03*
Y232400D03*
Y236850D03*
X681447Y240430D03*
X685600Y265100D03*
X685200Y259500D03*
X696003Y211743D03*
X696150Y203560D03*
X685547Y277530D03*
Y269230D03*
X685400Y285900D03*
X685547Y281730D03*
X682800Y307000D03*
X685547Y273430D03*
X671150Y470684D03*
X672500Y503900D03*
X696000Y504000D03*
X703138Y553602D03*
X718600Y569100D03*
X707800Y614500D03*
X716176Y594029D03*
X754320Y126510D03*
X782554Y514350D03*
X785284Y505600D03*
X777300Y518500D03*
X767619Y488799D03*
X743800Y508600D03*
X819800Y322500D03*
X805934Y480900D03*
X865550Y403400D03*
G54D60*
X197920Y712091D03*
Y736891D03*
X367762Y131001D03*
Y155801D03*
X833400Y451600D03*
Y426800D03*
X808200Y451600D03*
Y426800D03*
G54D144*
X892449Y237028D03*
Y230972D03*
X888551Y237028D03*
Y230972D03*
G54D135*
X679800Y634661D03*
Y599739D03*
G54D42*
X90157Y413583D03*
X309055Y157677D03*
G54D108*
X529093Y39585D03*
Y34585D03*
Y29585D03*
Y24585D03*
G54D33*
X43800Y660700D03*
X179518Y463748D03*
X145049Y687715D03*
X268300Y465400D03*
X251500Y590200D03*
X259707Y626253D03*
X268800Y639000D03*
X259100Y666100D03*
X325086Y522525D03*
X334200Y592000D03*
X278473Y637655D03*
X342100Y189874D03*
X366614Y639820D03*
X385170Y697180D03*
X468216Y53745D03*
X489786Y37907D03*
X774000Y66000D03*
X765900Y113000D03*
X837600Y475500D03*
G54D15*
X58010Y49110D03*
X75373Y506479D03*
X75405Y514077D03*
X69900Y506600D03*
X69778Y514077D03*
X46100Y671584D03*
X79570Y55060D03*
X81032Y514077D03*
X81068Y506466D03*
X105920Y481998D03*
X86659Y514077D03*
X86673Y506600D03*
X92000Y514000D03*
X101100Y511900D03*
X101113Y519377D03*
X142000Y512100D03*
X93531Y492941D03*
X132100Y648000D03*
X136100D03*
X113349Y693647D03*
X117449D03*
X121549Y691347D03*
X193000Y503000D03*
X146112Y513098D03*
X183320Y478098D03*
X178920D03*
X174715Y517020D03*
X187000Y517000D03*
X191100Y516500D03*
X170700Y517000D03*
X166600D03*
X178869Y516993D03*
X182874Y516991D03*
X160727Y516822D03*
X150112Y513098D03*
X156721Y516792D03*
X188400Y502900D03*
X185276Y632868D03*
X177100Y633600D03*
X173000D03*
X202560Y624066D03*
X197315Y622397D03*
X153700Y622800D03*
X189376Y632868D03*
X193476D03*
X181146Y633608D03*
X188400Y644000D03*
X149300Y645000D03*
X204357Y653486D03*
X191746Y653642D03*
X165000Y644300D03*
X155849Y695715D03*
X158349Y703515D03*
X230262Y515280D03*
X234348Y515214D03*
X238648D03*
X242700Y515220D03*
X243400Y639500D03*
X248215Y613187D03*
X219200Y640600D03*
X231300Y642100D03*
X211706Y637992D03*
X251900Y676300D03*
X238936Y663469D03*
X258500Y675800D03*
X266800Y667600D03*
X262645Y704501D03*
X270900Y670600D03*
X300200Y590200D03*
X304300D03*
X293150Y535300D03*
X289050D03*
X336500Y670100D03*
X391262Y68871D03*
X386027Y68840D03*
X362484Y196719D03*
X349004Y179630D03*
X363553Y476262D03*
X382550Y581406D03*
X360820Y586836D03*
X352480Y586164D03*
X378350Y581406D03*
X345287Y537559D03*
X391549Y560200D03*
X387733Y594590D03*
X348600Y635600D03*
X444722Y50015D03*
X603164Y540803D03*
X639040Y157710D03*
X634661Y367356D03*
X620822Y372464D03*
X623239Y337479D03*
X608500Y336000D03*
X640160Y521843D03*
X619400Y563800D03*
X623542Y563752D03*
X732000Y189000D03*
X734028Y178946D03*
X716650Y177600D03*
X710060Y324860D03*
X727000Y346300D03*
X731400Y356000D03*
X711700Y345300D03*
X696527Y457306D03*
X696700Y469900D03*
X702390Y488860D03*
X731676Y587729D03*
X707826Y601479D03*
X716345Y608390D03*
X777700Y74200D03*
X795600Y188400D03*
X790600D03*
X762200Y188800D03*
X745700Y189000D03*
X737000D03*
X775500Y188300D03*
X749900Y188700D03*
X785600Y188400D03*
X738465Y346235D03*
X777000Y489100D03*
X751400Y500800D03*
X777084Y523050D03*
X809349Y66636D03*
X841300Y57880D03*
X813449Y66636D03*
X805600Y188400D03*
X800600D03*
X810600D03*
X857569Y384933D03*
X861000Y403400D03*
X882913Y228798D03*
G54D126*
X627160Y538043D03*
G54D117*
X638780Y69685D03*
X629921D03*
X621063D03*
X641732Y117323D03*
X638780Y114567D03*
X635827Y120079D03*
X632873Y117323D03*
X629921Y114567D03*
X626969Y120079D03*
X624015Y117323D03*
X621063Y114567D03*
X618110Y120079D03*
X641732Y102362D03*
X638780Y99606D03*
X635827Y105118D03*
X632873Y102362D03*
X629921Y99606D03*
X621063D03*
X624015Y102362D03*
X626969Y105118D03*
X618110D03*
X641732Y87402D03*
X638780Y84646D03*
X635827Y90157D03*
X632873Y87402D03*
X626969Y90157D03*
X629921Y84646D03*
X624015Y87402D03*
X621063Y84646D03*
X618110Y90157D03*
X641732Y72441D03*
X635827Y75197D03*
X632873Y72441D03*
X626969Y75197D03*
X624015Y72441D03*
X618110Y75197D03*
X717520Y69685D03*
X708661D03*
X699803D03*
X720472Y117323D03*
X717520Y114567D03*
X714567Y120079D03*
X711613Y117323D03*
X708661Y114567D03*
X705709Y120079D03*
X702755Y117323D03*
X699803Y114567D03*
X696850Y120079D03*
X720472Y102362D03*
X717520Y99606D03*
X714567Y105118D03*
X711613Y102362D03*
X708661Y99606D03*
X699803D03*
X702755Y102362D03*
X705709Y105118D03*
X696850D03*
X720472Y87402D03*
X717520Y84646D03*
X714567Y90157D03*
X711613Y87402D03*
X705709Y90157D03*
X708661Y84646D03*
X702755Y87402D03*
X699803Y84646D03*
X696850Y90157D03*
X720472Y72441D03*
X714567Y75197D03*
X711613Y72441D03*
X705709Y75197D03*
X702755Y72441D03*
X696850Y75197D03*
G54D51*
X154724Y537795D03*
Y540945D03*
Y544094D03*
X157874Y537795D03*
Y540945D03*
Y544094D03*
X161023Y537795D03*
Y540945D03*
Y544094D03*
X154724Y597638D03*
Y600787D03*
Y603937D03*
X157874Y597638D03*
Y600787D03*
Y603937D03*
X161023Y597638D03*
Y600787D03*
Y603937D03*
X214567Y537795D03*
Y540945D03*
Y544094D03*
X217716Y537795D03*
Y540945D03*
Y544094D03*
X220866Y537795D03*
Y540945D03*
Y544094D03*
X214567Y597638D03*
Y600787D03*
Y603937D03*
X217716Y597638D03*
Y600787D03*
Y603937D03*
X220866Y597638D03*
Y600787D03*
Y603937D03*
X713386Y216929D03*
X716535D03*
X719685D03*
X713386Y213779D03*
X716535D03*
X719685D03*
X716535Y210630D03*
X719685D03*
X716535Y301968D03*
X719685D03*
X713386Y298819D03*
X716535D03*
X719685D03*
X713386Y295669D03*
X716535D03*
X719685D03*
X798425Y216929D03*
Y213779D03*
Y210630D03*
Y301968D03*
Y298819D03*
Y295669D03*
X801575Y216929D03*
X804724D03*
X801575Y213779D03*
X804724D03*
X801575Y210630D03*
Y301968D03*
Y298819D03*
X804724D03*
X801575Y295669D03*
X804724D03*
G54D52*
X207900Y637900D03*
X200532Y653603D03*
X215406Y637892D03*
X227500Y642000D03*
X212445Y653488D03*
X272503Y704737D03*
X299900Y582200D03*
X296500D03*
X322277Y548643D03*
X282600Y682100D03*
X345175Y113910D03*
X366632Y192804D03*
X360800Y491700D03*
X477300Y61200D03*
X538250Y68490D03*
X617023Y372365D03*
X679200Y459200D03*
X727676Y587629D03*
X794088Y508612D03*
X763801Y488719D03*
X755300Y500700D03*
X763147Y496327D03*
X747500Y500900D03*
X882871Y236212D03*
G54D16*
X43480Y53750D03*
X71800Y691500D03*
X84616Y60475D03*
X93614Y507152D03*
X115619Y712795D03*
X295018Y661382D03*
X278523Y736205D03*
X353972Y192744D03*
X352980Y641914D03*
X453800Y61500D03*
X533940Y73210D03*
X563870Y55203D03*
X628160Y565343D03*
X612500Y540600D03*
X724900Y493800D03*
X720200D03*
X751500Y54030D03*
X767247Y502427D03*
X800388Y522956D03*
G54D109*
X525520Y63570D03*
Y77410D03*
X710330Y497490D03*
Y483650D03*
G54D145*
X893634Y364633D03*
Y397685D03*
G54D43*
X135012Y521048D03*
X125788D03*
X135012Y514552D03*
X125788D03*
X270521Y612019D03*
Y618515D03*
X279745Y612019D03*
Y618515D03*
G54D127*
X633266Y540996D03*
Y535090D03*
X621054D03*
Y540996D03*
G54D61*
X178543Y728500D03*
X156657D03*
G54D34*
X47400Y660700D03*
X183118Y463748D03*
X148649Y687715D03*
X271900Y465400D03*
X255100Y590200D03*
X263307Y626253D03*
X272400Y639000D03*
X262700Y666100D03*
X328686Y522525D03*
X337800Y592000D03*
X282073Y637655D03*
X345700Y189874D03*
X370214Y639820D03*
X388770Y697180D03*
X471816Y53745D03*
X493386Y37907D03*
X777600Y66000D03*
X769500Y113000D03*
X841200Y475500D03*
G54D25*
X33265Y532638D03*
X61454Y639950D03*
X38733Y679946D03*
X131262Y603311D03*
X132018Y617677D03*
X131250Y599250D03*
X132753Y609777D03*
X109300Y597000D03*
Y601000D03*
Y609000D03*
Y605000D03*
Y613000D03*
X109800Y621000D03*
X109300Y617000D03*
X109899Y701465D03*
X137649Y687715D03*
X179544Y459767D03*
Y469867D03*
X174341Y495710D03*
X200200Y495600D03*
X208700Y499300D03*
X268000Y458200D03*
X268400Y490300D03*
X268000Y470300D03*
X239900Y581100D03*
X239570Y556658D03*
X263841Y543759D03*
X262900Y567300D03*
X266800Y572100D03*
X239618Y568821D03*
Y572821D03*
X240000Y576900D03*
X242293Y532802D03*
X273367Y557480D03*
X256220Y532870D03*
X267600Y605500D03*
X232900Y637600D03*
X266600Y643000D03*
X258300D03*
X259696Y630071D03*
X275450Y602700D03*
X267200Y723500D03*
X340247Y226992D03*
X340282Y256474D03*
X327121Y526309D03*
X291455Y546906D03*
X291500Y551300D03*
X326780Y531380D03*
X332465Y539609D03*
X326316Y543816D03*
X305051Y535356D03*
X287600Y617000D03*
X302000Y616384D03*
X291318Y684153D03*
X345631Y242261D03*
X345722Y247314D03*
X342794Y268585D03*
X343091Y272906D03*
X347800Y511900D03*
Y503600D03*
X387600Y589571D03*
X386579Y585543D03*
X386300Y576500D03*
Y572500D03*
X387700Y602100D03*
X387736Y619701D03*
X387700Y606200D03*
X387586Y628081D03*
X387550Y637348D03*
X385225Y693371D03*
X385700Y671800D03*
X388655Y684644D03*
X386200Y677900D03*
X434185Y38057D03*
X442616Y38147D03*
X437081Y56947D03*
X442685Y30457D03*
Y26157D03*
X442585Y21957D03*
X489800Y30000D03*
Y22000D03*
Y26000D03*
X525500Y49400D03*
Y53600D03*
X559300Y82000D03*
X630322Y379591D03*
X662200Y443200D03*
X639500Y553700D03*
X681642Y244547D03*
X694900Y249400D03*
X696100Y207600D03*
X720200Y564600D03*
Y560600D03*
X716176Y598329D03*
X767734Y518500D03*
X740100Y501300D03*
X811800Y322500D03*
X814572Y393639D03*
X814867Y398968D03*
X805900Y473500D03*
G54D118*
X651575Y20039D03*
X608267D03*
X641732Y126811D03*
X624015D03*
X651575Y72441D03*
X608267D03*
X730315Y20039D03*
X687007D03*
X720472Y126811D03*
X702755D03*
X730315Y72441D03*
X687007D03*
G54D136*
X668500Y710050D03*
Y709550D03*
G54D70*
X339331Y49803D03*
X360669Y91929D03*
G54D146*
G01X13215Y-125739D02*
X14089Y-124864D01*
X14744Y-123406D01*
X15181Y-121363D01*
X14744Y-119614D01*
X13871Y-118447D01*
X12342Y-117572D01*
X6447D01*
Y-135072D01*
X13652D01*
X15181Y-133906D01*
X16054Y-132155D01*
X16491Y-130114D01*
X16054Y-128072D01*
X14744Y-126322D01*
X13215Y-125739D01*
X6447D01*
G01X25912Y-135072D02*
Y-123406D01*
G01Y-125739D02*
X27004Y-124572D01*
X28096Y-123697D01*
X29624Y-123406D01*
X30715Y-123697D01*
X32026Y-124572D01*
G01X41884Y-140322D02*
X43194Y-140905D01*
X44941Y-140322D01*
X46032Y-139156D01*
X46906Y-137697D01*
X48215Y-133031D01*
X51054Y-123406D01*
G01X44067D02*
X48215Y-133031D01*
G01X67462Y-124864D02*
X65934Y-123697D01*
X64624Y-123406D01*
X62877Y-123989D01*
X61567Y-125155D01*
X60694Y-127197D01*
X60475Y-129239D01*
X60694Y-131281D01*
X61567Y-133031D01*
X62877Y-134489D01*
X64624Y-135072D01*
X66152Y-134489D01*
X67462Y-133322D01*
G01X78194Y-127197D02*
X85181D01*
X84526Y-125155D01*
X83434Y-123989D01*
X81906Y-123406D01*
X80377Y-123697D01*
X79067Y-124572D01*
X78194Y-126614D01*
X77757Y-128364D01*
Y-130114D01*
X78194Y-131864D01*
X79286Y-133614D01*
X80596Y-134780D01*
X82124Y-135072D01*
X83652Y-134489D01*
X85181Y-132739D01*
G01X121272Y-119031D02*
X119962Y-118155D01*
X118434Y-117572D01*
X116687D01*
X114722Y-118447D01*
X113194Y-119905D01*
X112102Y-121656D01*
X111229Y-124572D01*
X111010Y-127197D01*
X111447Y-129822D01*
X112102Y-131572D01*
X113412Y-133322D01*
X114941Y-134489D01*
X116469Y-135072D01*
X117997D01*
X119526Y-134489D01*
X120836Y-133614D01*
X121928Y-132448D01*
G01X137899Y-135072D02*
Y-123406D01*
G01Y-125447D02*
X137026Y-124281D01*
X135715Y-123697D01*
X134187Y-123406D01*
X132659Y-123989D01*
X131349Y-125155D01*
X130475Y-126905D01*
X130039Y-129239D01*
X130475Y-131572D01*
X131349Y-133322D01*
X132659Y-134489D01*
X134187Y-135072D01*
X135715Y-134780D01*
X137026Y-133906D01*
X137899Y-132739D01*
G01X147757Y-135072D02*
Y-123406D01*
G01Y-126322D02*
X148631Y-124864D01*
X149941Y-123697D01*
X151687Y-123406D01*
X153215Y-123697D01*
X154526Y-124864D01*
X155181Y-126905D01*
Y-135072D01*
G01X164384Y-140322D02*
X165694Y-140905D01*
X167441Y-140322D01*
X168532Y-139156D01*
X169406Y-137697D01*
X170715Y-133031D01*
X173554Y-123406D01*
G01X166567D02*
X170715Y-133031D01*
G01X186469Y-135072D02*
X185159Y-134780D01*
X183849Y-133614D01*
X182975Y-131572D01*
X182539Y-129239D01*
X182975Y-126905D01*
X183849Y-124864D01*
X185159Y-123697D01*
X186469Y-123406D01*
X187779Y-123697D01*
X189089Y-124864D01*
X189962Y-126905D01*
X190181Y-129239D01*
X189962Y-131572D01*
X189089Y-133614D01*
X187779Y-134780D01*
X186469Y-135072D01*
G01X200257D02*
Y-123406D01*
G01Y-126322D02*
X201131Y-124864D01*
X202441Y-123697D01*
X204187Y-123406D01*
X205715Y-123697D01*
X207026Y-124864D01*
X207681Y-126905D01*
Y-135072D01*
G01X236349Y-117572D02*
X241589D01*
G01X238969D02*
Y-135072D01*
G01X236349D02*
X241589D01*
G01X256469D02*
X254722Y-134780D01*
X253194Y-133614D01*
X251884Y-131864D01*
X251010Y-129822D01*
X250574Y-127489D01*
Y-125155D01*
X251010Y-122822D01*
X251884Y-120780D01*
X253194Y-119031D01*
X254722Y-117864D01*
X256469Y-117572D01*
X258215Y-117864D01*
X259744Y-119031D01*
X261054Y-120780D01*
X261928Y-122822D01*
X262364Y-125155D01*
Y-127489D01*
X261928Y-129822D01*
X261054Y-131864D01*
X259744Y-133614D01*
X258215Y-134780D01*
X256469Y-135072D01*
G01X268292D02*
Y-117572D01*
X273969Y-132155D01*
X279646Y-117572D01*
Y-135072D01*
G01X307877Y-140905D02*
X305694Y-137989D01*
X304602Y-135072D01*
Y-123406D01*
X305694Y-120489D01*
X307877Y-117572D01*
G01X321010Y-123406D02*
X323631Y-135072D01*
X326469Y-123406D01*
X329307Y-135072D01*
X331928Y-123406D01*
G01X340039Y-135655D02*
X347899Y-117572D01*
G01X376349D02*
X381589D01*
G01X378969D02*
Y-135072D01*
G01X376349D02*
X381589D01*
G01X396469D02*
X394722Y-134780D01*
X393194Y-133614D01*
X391884Y-131864D01*
X391010Y-129822D01*
X390574Y-127489D01*
Y-125155D01*
X391010Y-122822D01*
X391884Y-120780D01*
X393194Y-119031D01*
X394722Y-117864D01*
X396469Y-117572D01*
X398215Y-117864D01*
X399744Y-119031D01*
X401054Y-120780D01*
X401928Y-122822D01*
X402364Y-125155D01*
Y-127489D01*
X401928Y-129822D01*
X401054Y-131864D01*
X399744Y-133614D01*
X398215Y-134780D01*
X396469Y-135072D01*
G01X418772Y-119031D02*
X417462Y-118155D01*
X415934Y-117572D01*
X414187D01*
X412222Y-118447D01*
X410694Y-119905D01*
X409602Y-121656D01*
X408729Y-124572D01*
X408510Y-127197D01*
X408947Y-129822D01*
X409602Y-131572D01*
X410912Y-133322D01*
X412441Y-134489D01*
X413969Y-135072D01*
X415497D01*
X417026Y-134489D01*
X418336Y-133614D01*
X419428Y-132448D01*
G01X432561Y-140905D02*
X434744Y-137989D01*
X435836Y-135072D01*
Y-123406D01*
X434744Y-120489D01*
X432561Y-117572D01*
G01X180792Y-90072D02*
Y-72572D01*
X186469Y-87155D01*
X192146Y-72572D01*
Y-90072D01*
G01X203969D02*
X202659Y-89780D01*
X201349Y-88614D01*
X200475Y-86572D01*
X200039Y-84239D01*
X200475Y-81905D01*
X201349Y-79864D01*
X202659Y-78697D01*
X203969Y-78406D01*
X205279Y-78697D01*
X206589Y-79864D01*
X207462Y-81905D01*
X207681Y-84239D01*
X207462Y-86572D01*
X206589Y-88614D01*
X205279Y-89780D01*
X203969Y-90072D01*
G01X225399Y-72572D02*
Y-90072D01*
G01Y-87448D02*
X224526Y-88906D01*
X223215Y-89780D01*
X221687Y-90072D01*
X219941Y-89489D01*
X218631Y-88031D01*
X217757Y-86281D01*
X217539Y-84239D01*
X217757Y-82197D01*
X218631Y-80447D01*
X219941Y-78989D01*
X221687Y-78406D01*
X223215Y-78697D01*
X224307Y-79281D01*
X225399Y-80447D01*
G01X235694Y-82197D02*
X242681D01*
X242026Y-80155D01*
X240934Y-78989D01*
X239406Y-78406D01*
X237877Y-78697D01*
X236567Y-79572D01*
X235694Y-81614D01*
X235257Y-83364D01*
Y-85114D01*
X235694Y-86864D01*
X236786Y-88614D01*
X238096Y-89780D01*
X239624Y-90072D01*
X241152Y-89489D01*
X242681Y-87739D01*
G01X256469Y-90072D02*
Y-72572D01*
G01X490269Y-135072D02*
Y-117572D01*
X487649Y-121072D01*
G01Y-135072D02*
X492889D01*
G01X503621Y-127781D02*
X505149Y-125739D01*
X506459Y-124572D01*
X508206Y-123989D01*
X509734Y-124572D01*
X510826Y-125739D01*
X511699Y-127489D01*
X511917Y-129530D01*
X511699Y-131281D01*
X510826Y-133031D01*
X509515Y-134489D01*
X507987Y-135072D01*
X506241Y-134489D01*
X504712Y-132739D01*
X503839Y-130114D01*
X503621Y-127197D01*
X504057Y-123406D01*
X504712Y-121363D01*
X505804Y-119322D01*
X507332Y-117864D01*
X508861Y-117572D01*
X510389Y-118155D01*
X511481Y-119614D01*
G01X520466Y-131572D02*
X521775Y-133614D01*
X523522Y-134780D01*
X525487Y-135072D01*
X527234Y-134780D01*
X528981Y-133322D01*
X530072Y-131572D01*
X530291Y-129822D01*
X529854Y-127781D01*
X528326Y-126322D01*
X526797Y-125739D01*
X524832D01*
G01X526797D02*
X528107Y-124864D01*
X529199Y-123406D01*
X529636Y-121656D01*
X529199Y-119905D01*
X528107Y-118447D01*
X526142Y-117572D01*
X524177Y-117864D01*
X522212Y-119031D01*
G01X542769Y-135072D02*
Y-117572D01*
X540149Y-121072D01*
G01Y-135072D02*
X545389D01*
G01X560269D02*
X561797Y-134780D01*
X563544Y-133906D01*
X564636Y-132448D01*
X565072Y-130405D01*
X564636Y-128364D01*
X563326Y-126614D01*
X561361Y-125739D01*
X559177D01*
X557867Y-125155D01*
X556775Y-123697D01*
X556339Y-121656D01*
X556994Y-119614D01*
X558522Y-118155D01*
X560269Y-117572D01*
X562015Y-118155D01*
X563544Y-119614D01*
X564199Y-121656D01*
X563762Y-123697D01*
X562671Y-125155D01*
X561361Y-125739D01*
X559177D01*
X557212Y-126614D01*
X555902Y-128364D01*
X555466Y-130405D01*
X555902Y-132448D01*
X556994Y-133906D01*
X558741Y-134780D01*
X560269Y-135072D01*
G01X477152Y-90072D02*
Y-72572D01*
X482392D01*
X484139Y-73447D01*
X485449Y-75489D01*
X485886Y-77822D01*
X485449Y-80155D01*
X484357Y-81905D01*
X482392Y-82781D01*
X477152D01*
G01X503822Y-74031D02*
X502512Y-73155D01*
X500984Y-72572D01*
X499237D01*
X497272Y-73447D01*
X495744Y-74905D01*
X494652Y-76656D01*
X493779Y-79572D01*
X493560Y-82197D01*
X493997Y-84822D01*
X494652Y-86572D01*
X495962Y-88322D01*
X497491Y-89489D01*
X499019Y-90072D01*
X500547D01*
X502076Y-89489D01*
X503386Y-88614D01*
X504478Y-87448D01*
G01X518265Y-80739D02*
X519139Y-79864D01*
X519794Y-78406D01*
X520231Y-76363D01*
X519794Y-74614D01*
X518921Y-73447D01*
X517392Y-72572D01*
X511497D01*
Y-90072D01*
X518702D01*
X520231Y-88906D01*
X521104Y-87155D01*
X521541Y-85114D01*
X521104Y-83072D01*
X519794Y-81322D01*
X518265Y-80739D01*
X511497D01*
G01X527469Y-95905D02*
X540569D01*
G01X546497Y-90072D02*
Y-72572D01*
X556541Y-90072D01*
Y-72572D01*
G01X569019Y-90072D02*
X567272Y-89780D01*
X565744Y-88614D01*
X564434Y-86864D01*
X563560Y-84822D01*
X563124Y-82489D01*
Y-80155D01*
X563560Y-77822D01*
X564434Y-75780D01*
X565744Y-74031D01*
X567272Y-72864D01*
X569019Y-72572D01*
X570765Y-72864D01*
X572294Y-74031D01*
X573604Y-75780D01*
X574478Y-77822D01*
X574914Y-80155D01*
Y-82489D01*
X574478Y-84822D01*
X573604Y-86864D01*
X572294Y-88614D01*
X570765Y-89780D01*
X569019Y-90072D01*
G01X647421Y-120489D02*
X648731Y-118739D01*
X650259Y-117864D01*
X652006Y-117572D01*
X654189Y-118155D01*
X655717Y-119614D01*
X656154Y-121363D01*
X655936Y-123114D01*
X655062Y-124572D01*
X650696Y-127489D01*
X648731Y-129530D01*
X647421Y-132448D01*
X646984Y-135072D01*
X656154D01*
G01X619860Y-72572D02*
X625319Y-90072D01*
X630778Y-72572D01*
G01X647186Y-90072D02*
X638452D01*
Y-72572D01*
X647186D01*
G01X643692Y-81030D02*
X638452D01*
G01X655952Y-90072D02*
Y-72572D01*
X661411D01*
X663157Y-73447D01*
X664249Y-74614D01*
X664686Y-76947D01*
X664249Y-79281D01*
X662939Y-80739D01*
X661411Y-81614D01*
X655952D01*
G01X661411D02*
X664686Y-90072D01*
G01X677819Y-90655D02*
X677382Y-90364D01*
Y-89780D01*
X677819Y-89489D01*
X678256Y-89780D01*
Y-90364D01*
X677819Y-90655D01*
G01X757769Y-117572D02*
Y-135072D01*
G01X752747Y-117572D02*
X762791D01*
G01X769592Y-135072D02*
Y-117572D01*
X775269Y-132155D01*
X780946Y-117572D01*
Y-135072D01*
G01X787310D02*
X792769Y-117572D01*
X798228Y-135072D01*
G01X796262Y-128947D02*
X789275D01*
G01X805684Y-132739D02*
X807431Y-134197D01*
X809396Y-135072D01*
X811142D01*
X812889Y-134197D01*
X814199Y-132739D01*
X814854Y-130697D01*
X814417Y-128656D01*
X813326Y-126905D01*
X811361Y-125739D01*
X808741Y-125155D01*
X807212Y-123989D01*
X806557Y-121947D01*
X806994Y-119905D01*
X808086Y-118447D01*
X809614Y-117572D01*
X811142D01*
X812671Y-118155D01*
X813981Y-119614D01*
G01X822966Y-135072D02*
Y-117572D01*
G01X831262D02*
X822966Y-128364D01*
G01X832572Y-135072D02*
X826677Y-123406D01*
G01X753402Y-72572D02*
Y-90072D01*
X762136D01*
G01X779199D02*
Y-78406D01*
G01Y-80447D02*
X778326Y-79281D01*
X777015Y-78697D01*
X775487Y-78406D01*
X773959Y-78989D01*
X772649Y-80155D01*
X771775Y-81905D01*
X771339Y-84239D01*
X771775Y-86572D01*
X772649Y-88322D01*
X773959Y-89489D01*
X775487Y-90072D01*
X777015Y-89780D01*
X778326Y-88906D01*
X779199Y-87739D01*
G01X788184Y-95322D02*
X789494Y-95905D01*
X791241Y-95322D01*
X792332Y-94156D01*
X793206Y-92697D01*
X794515Y-88031D01*
X797354Y-78406D01*
G01X790367D02*
X794515Y-88031D01*
G01X806994Y-82197D02*
X813981D01*
X813326Y-80155D01*
X812234Y-78989D01*
X810706Y-78406D01*
X809177Y-78697D01*
X807867Y-79572D01*
X806994Y-81614D01*
X806557Y-83364D01*
Y-85114D01*
X806994Y-86864D01*
X808086Y-88614D01*
X809396Y-89780D01*
X810924Y-90072D01*
X812452Y-89489D01*
X813981Y-87739D01*
G01X824712Y-90072D02*
Y-78406D01*
G01Y-80739D02*
X825804Y-79572D01*
X826896Y-78697D01*
X828424Y-78406D01*
X829515Y-78697D01*
X830826Y-79572D01*
G01X917819Y-135072D02*
X916072Y-134780D01*
X914544Y-133614D01*
X913234Y-131864D01*
X912360Y-129822D01*
X911924Y-127489D01*
Y-125155D01*
X912360Y-122822D01*
X913234Y-120780D01*
X914544Y-119031D01*
X916072Y-117864D01*
X917819Y-117572D01*
X919565Y-117864D01*
X921094Y-119031D01*
X922404Y-120780D01*
X923278Y-122822D01*
X923714Y-125155D01*
Y-127489D01*
X923278Y-129822D01*
X922404Y-131864D01*
X921094Y-133614D01*
X919565Y-134780D01*
X917819Y-135072D01*
G01X919565Y-130405D02*
X922186Y-135072D01*
G01X930516Y-117572D02*
Y-130114D01*
X931389Y-132739D01*
X933136Y-134489D01*
X935319Y-135072D01*
X937502Y-134489D01*
X939249Y-132739D01*
X940122Y-130114D01*
Y-117572D01*
G01X950199D02*
X955439D01*
G01X952819D02*
Y-135072D01*
G01X950199D02*
X955439D01*
G01X965297D02*
Y-117572D01*
X975341Y-135072D01*
Y-117572D01*
G01X992622Y-119031D02*
X991312Y-118155D01*
X989784Y-117572D01*
X988037D01*
X986072Y-118447D01*
X984544Y-119905D01*
X983452Y-121656D01*
X982579Y-124572D01*
X982360Y-127197D01*
X982797Y-129822D01*
X983452Y-131572D01*
X984762Y-133322D01*
X986291Y-134489D01*
X987819Y-135072D01*
X989347D01*
X990876Y-134489D01*
X992186Y-133614D01*
X993278Y-132448D01*
G01X1005319Y-135072D02*
Y-127197D01*
X1000952Y-117572D01*
G01X1009686D02*
X1005319Y-127197D01*
G01X895516Y-90072D02*
Y-72572D01*
X899882D01*
X901629Y-73447D01*
X902939Y-74614D01*
X904031Y-76363D01*
X904904Y-78406D01*
X905122Y-81322D01*
X904904Y-84239D01*
X904031Y-86281D01*
X902939Y-88031D01*
X901629Y-89197D01*
X899882Y-90072D01*
X895516D01*
G01X914544Y-82197D02*
X921531D01*
X920876Y-80155D01*
X919784Y-78989D01*
X918256Y-78406D01*
X916727Y-78697D01*
X915417Y-79572D01*
X914544Y-81614D01*
X914107Y-83364D01*
Y-85114D01*
X914544Y-86864D01*
X915636Y-88614D01*
X916946Y-89780D01*
X918474Y-90072D01*
X920002Y-89489D01*
X921531Y-87739D01*
G01X932044Y-88031D02*
X933136Y-89197D01*
X934664Y-90072D01*
X935974D01*
X937284Y-89489D01*
X938157Y-88614D01*
X938594Y-87448D01*
X938376Y-85697D01*
X937502Y-84822D01*
X933572Y-83072D01*
X932699Y-81030D01*
X933136Y-79572D01*
X934009Y-78697D01*
X935319Y-78406D01*
X936629Y-78697D01*
X937939Y-79572D01*
G01X952819Y-78406D02*
Y-90072D01*
G01Y-73739D02*
X952382Y-73447D01*
Y-72864D01*
X952819Y-72572D01*
X953256Y-72864D01*
Y-73447D01*
X952819Y-73739D01*
G01X967262Y-94447D02*
X968791Y-95614D01*
X970537Y-95905D01*
X972065Y-95614D01*
X973376Y-94156D01*
X974249Y-92114D01*
Y-78406D01*
G01Y-80739D02*
X973376Y-79572D01*
X972065Y-78697D01*
X970537Y-78406D01*
X968791Y-78989D01*
X967699Y-80155D01*
X966825Y-82197D01*
X966389Y-84239D01*
X966607Y-85989D01*
X967481Y-88031D01*
X968791Y-89489D01*
X970537Y-90072D01*
X971847Y-89780D01*
X973376Y-88614D01*
X974249Y-87448D01*
G01X984107Y-90072D02*
Y-78406D01*
G01Y-81322D02*
X984981Y-79864D01*
X986291Y-78697D01*
X988037Y-78406D01*
X989565Y-78697D01*
X990876Y-79864D01*
X991531Y-81905D01*
Y-90072D01*
G01X1002044Y-82197D02*
X1009031D01*
X1008376Y-80155D01*
X1007284Y-78989D01*
X1005756Y-78406D01*
X1004227Y-78697D01*
X1002917Y-79572D01*
X1002044Y-81614D01*
X1001607Y-83364D01*
Y-85114D01*
X1002044Y-86864D01*
X1003136Y-88614D01*
X1004446Y-89780D01*
X1005974Y-90072D01*
X1007502Y-89489D01*
X1009031Y-87739D01*
G01X1019762Y-90072D02*
Y-78406D01*
G01Y-80739D02*
X1020854Y-79572D01*
X1021946Y-78697D01*
X1023474Y-78406D01*
X1024565Y-78697D01*
X1025876Y-79572D01*
G01X1066519Y-117572D02*
X1064772Y-118155D01*
X1063462Y-119614D01*
X1062589Y-121363D01*
X1061934Y-123697D01*
X1061716Y-126322D01*
X1061934Y-128947D01*
X1062589Y-131281D01*
X1063462Y-133031D01*
X1064772Y-134489D01*
X1066519Y-135072D01*
X1068265Y-134489D01*
X1069576Y-133031D01*
X1070449Y-131281D01*
X1071104Y-128947D01*
X1071322Y-126322D01*
X1071104Y-123697D01*
X1070449Y-121363D01*
X1069576Y-119614D01*
X1068265Y-118155D01*
X1066519Y-117572D01*
G01X1084019Y-135072D02*
X1085547Y-134780D01*
X1087294Y-133906D01*
X1088386Y-132448D01*
X1088822Y-130405D01*
X1088386Y-128364D01*
X1087076Y-126614D01*
X1085111Y-125739D01*
X1082927D01*
X1081617Y-125155D01*
X1080525Y-123697D01*
X1080089Y-121656D01*
X1080744Y-119614D01*
X1082272Y-118155D01*
X1084019Y-117572D01*
X1085765Y-118155D01*
X1087294Y-119614D01*
X1087949Y-121656D01*
X1087512Y-123697D01*
X1086421Y-125155D01*
X1085111Y-125739D01*
X1082927D01*
X1080962Y-126614D01*
X1079652Y-128364D01*
X1079216Y-130405D01*
X1079652Y-132448D01*
X1080744Y-133906D01*
X1082491Y-134780D01*
X1084019Y-135072D01*
G01X1097589Y-135655D02*
X1105449Y-117572D01*
G01X1119019D02*
X1117272Y-118155D01*
X1115962Y-119614D01*
X1115089Y-121363D01*
X1114434Y-123697D01*
X1114216Y-126322D01*
X1114434Y-128947D01*
X1115089Y-131281D01*
X1115962Y-133031D01*
X1117272Y-134489D01*
X1119019Y-135072D01*
X1120765Y-134489D01*
X1122076Y-133031D01*
X1122949Y-131281D01*
X1123604Y-128947D01*
X1123822Y-126322D01*
X1123604Y-123697D01*
X1122949Y-121363D01*
X1122076Y-119614D01*
X1120765Y-118155D01*
X1119019Y-117572D01*
G01X1136082Y-135072D02*
X1136519Y-131281D01*
X1137174Y-128072D01*
X1138047Y-125155D01*
X1139139Y-121947D01*
X1140886Y-117572D01*
X1132152D01*
G01X1150089Y-135655D02*
X1157949Y-117572D01*
G01X1167371Y-120489D02*
X1168681Y-118739D01*
X1170209Y-117864D01*
X1171956Y-117572D01*
X1174139Y-118155D01*
X1175667Y-119614D01*
X1176104Y-121363D01*
X1175886Y-123114D01*
X1175012Y-124572D01*
X1170646Y-127489D01*
X1168681Y-129530D01*
X1167371Y-132448D01*
X1166934Y-135072D01*
X1176104D01*
G01X1189019Y-117572D02*
X1187272Y-118155D01*
X1185962Y-119614D01*
X1185089Y-121363D01*
X1184434Y-123697D01*
X1184216Y-126322D01*
X1184434Y-128947D01*
X1185089Y-131281D01*
X1185962Y-133031D01*
X1187272Y-134489D01*
X1189019Y-135072D01*
X1190765Y-134489D01*
X1192076Y-133031D01*
X1192949Y-131281D01*
X1193604Y-128947D01*
X1193822Y-126322D01*
X1193604Y-123697D01*
X1192949Y-121363D01*
X1192076Y-119614D01*
X1190765Y-118155D01*
X1189019Y-117572D01*
G01X1206519Y-135072D02*
Y-117572D01*
X1203899Y-121072D01*
G01Y-135072D02*
X1209139D01*
G01X1223582D02*
X1224019Y-131281D01*
X1224674Y-128072D01*
X1225547Y-125155D01*
X1226639Y-121947D01*
X1228386Y-117572D01*
X1219652D01*
G01X1114216Y-90072D02*
Y-72572D01*
X1118582D01*
X1120329Y-73447D01*
X1121639Y-74614D01*
X1122731Y-76363D01*
X1123604Y-78406D01*
X1123822Y-81322D01*
X1123604Y-84239D01*
X1122731Y-86281D01*
X1121639Y-88031D01*
X1120329Y-89197D01*
X1118582Y-90072D01*
X1114216D01*
G01X1140449D02*
Y-78406D01*
G01Y-80447D02*
X1139576Y-79281D01*
X1138265Y-78697D01*
X1136737Y-78406D01*
X1135209Y-78989D01*
X1133899Y-80155D01*
X1133025Y-81905D01*
X1132589Y-84239D01*
X1133025Y-86572D01*
X1133899Y-88322D01*
X1135209Y-89489D01*
X1136737Y-90072D01*
X1138265Y-89780D01*
X1139576Y-88906D01*
X1140449Y-87739D01*
G01X1154019Y-72572D02*
Y-90072D01*
G01X1150962Y-78406D02*
X1157076D01*
G01X1168244Y-82197D02*
X1175231D01*
X1174576Y-80155D01*
X1173484Y-78989D01*
X1171956Y-78406D01*
X1170427Y-78697D01*
X1169117Y-79572D01*
X1168244Y-81614D01*
X1167807Y-83364D01*
Y-85114D01*
X1168244Y-86864D01*
X1169336Y-88614D01*
X1170646Y-89780D01*
X1172174Y-90072D01*
X1173702Y-89489D01*
X1175231Y-87739D01*
G54D53*
X207900Y641500D03*
X200532Y657203D03*
X215406Y641492D03*
X227500Y645600D03*
X212445Y657088D03*
X272503Y708337D03*
X299900Y585800D03*
X296500D03*
X322277Y552243D03*
X282600Y685700D03*
X345175Y117510D03*
X366632Y196404D03*
X360800Y495300D03*
X477300Y64800D03*
X538250Y72090D03*
X617023Y375965D03*
X679200Y462800D03*
X727676Y591229D03*
X794088Y512212D03*
X763801Y492319D03*
X755300Y504300D03*
X763147Y499927D03*
X747500Y504500D03*
X882871Y239812D03*
G54D119*
X652756Y180000D03*
X865353Y332598D03*
G54D44*
X90854Y639150D03*
X98454D03*
X90854Y647050D03*
X98454D03*
X87050Y682154D03*
X94650D03*
X87100Y674400D03*
X94700D03*
X87900Y722700D03*
X95500D03*
X322740Y611500D03*
X330340D03*
X322740Y619400D03*
X330340D03*
X320774Y691270D03*
X328374D03*
X320774Y683370D03*
X328374D03*
X352200Y105700D03*
X359800D03*
X512857Y25444D03*
X520457D03*
X511349Y34452D03*
X503749D03*
Y42252D03*
X511349D03*
X602860Y528543D03*
X667600Y436900D03*
X660000D03*
X622300Y473000D03*
X614700D03*
X622300Y481000D03*
X614700D03*
X610460Y528543D03*
X669300Y704200D03*
X661700D03*
X669300Y696500D03*
X661700D03*
X669300Y688800D03*
X661700D03*
X721300Y433500D03*
X728900D03*
X721300Y441300D03*
X728900D03*
X721300Y449100D03*
X728900D03*
X721300Y456900D03*
X728900D03*
X721300Y464700D03*
X728900D03*
X684700Y536600D03*
X677100D03*
X683000Y567400D03*
X675400D03*
X684676Y559729D03*
X677076D03*
X684676Y544329D03*
X677076D03*
X684676Y552029D03*
X677076D03*
X683276Y579571D03*
X675676D03*
X835654Y481650D03*
X843254D03*
X835900Y469500D03*
X843500D03*
G54D71*
X339331Y91929D03*
X360669Y49803D03*
G54D128*
X633216Y539027D03*
Y537059D03*
X621104D03*
Y539027D03*
G54D62*
X274245Y551954D03*
Y549394D03*
Y546834D03*
X281645D03*
Y549394D03*
Y551954D03*
G54D35*
X49900Y674984D03*
X117700Y518800D03*
X85500Y636300D03*
X81784Y671500D03*
X203650Y636650D03*
X207060Y633220D03*
X170100Y708200D03*
X210520Y632910D03*
X247400Y643000D03*
X225400Y716600D03*
X263000Y679300D03*
X328659Y539659D03*
X317600Y610400D03*
X322100Y645300D03*
X314920Y682520D03*
X311704Y715720D03*
X366699Y204821D03*
X521800Y53400D03*
X559200Y44100D03*
X633800Y341500D03*
X614000Y340900D03*
X645300Y529800D03*
X702460Y484650D03*
X728559Y477898D03*
X676194Y589729D03*
X723676Y591229D03*
X776200Y54800D03*
X786600Y419800D03*
X794500Y501200D03*
X757099Y526566D03*
X826284Y505500D03*
X883100Y224700D03*
G54D26*
X36665Y532638D03*
X64854Y639950D03*
X42133Y679946D03*
X134662Y603311D03*
X135418Y617677D03*
X134650Y599250D03*
X136153Y609777D03*
X112700Y597000D03*
Y601000D03*
Y609000D03*
Y605000D03*
Y613000D03*
X113200Y621000D03*
X112700Y617000D03*
X113299Y701465D03*
X141049Y687715D03*
X182944Y459767D03*
Y469867D03*
X177741Y495710D03*
X203600Y495600D03*
X271400Y458200D03*
X271800Y490300D03*
X271400Y470300D03*
X212100Y499300D03*
X243300Y581100D03*
X242970Y556658D03*
X267241Y543759D03*
X266300Y567300D03*
X270200Y572100D03*
X243018Y568821D03*
Y572821D03*
X243400Y576900D03*
X245693Y532802D03*
X259620Y532870D03*
X271000Y605500D03*
X236300Y637600D03*
X270000Y643000D03*
X261700D03*
X263096Y630071D03*
X270600Y723500D03*
X330521Y526309D03*
X294855Y546906D03*
X294900Y551300D03*
X276767Y557480D03*
X330180Y531380D03*
X335865Y539609D03*
X329716Y543816D03*
X308451Y535356D03*
X291000Y617000D03*
X305400Y616384D03*
X278850Y602700D03*
X294718Y684153D03*
X343647Y226992D03*
X349031Y242261D03*
X349122Y247314D03*
X343682Y256474D03*
X346194Y268585D03*
X346491Y272906D03*
X351200Y511900D03*
Y503600D03*
X391000Y589571D03*
X389979Y585543D03*
X389700Y576500D03*
Y572500D03*
X391100Y602100D03*
X391136Y619701D03*
X391100Y606200D03*
X390986Y628081D03*
X390950Y637348D03*
X388625Y693371D03*
X389100Y671800D03*
X392055Y684644D03*
X389600Y677900D03*
X437585Y38057D03*
X446016Y38147D03*
X440481Y56947D03*
X446085Y30457D03*
Y26157D03*
X445985Y21957D03*
X493200Y30000D03*
Y22000D03*
Y26000D03*
X528900Y49400D03*
Y53600D03*
X562700Y82000D03*
X633722Y379591D03*
X665600Y443200D03*
X642900Y553700D03*
X685042Y244547D03*
X698300Y249400D03*
X699500Y207600D03*
X723600Y564600D03*
Y560600D03*
X719576Y598329D03*
X771134Y518500D03*
X743500Y501300D03*
X815200Y322500D03*
X817972Y393639D03*
X818267Y398968D03*
X809300Y473500D03*
G54D137*
X761800Y438310D03*
Y461858D03*
G54D80*
X346457Y66850D03*
Y57007D03*
X353543Y70787D03*
Y62913D03*
Y55039D03*
X346457Y74724D03*
Y84567D03*
X353543Y86535D03*
Y78661D03*
G54D17*
X43480Y48150D03*
X71800Y685900D03*
X84616Y54875D03*
X93614Y501552D03*
X115619Y707195D03*
X295018Y655782D03*
X278523Y730605D03*
X353972Y187144D03*
X352980Y636314D03*
X453800Y55900D03*
X533940Y67610D03*
X563870Y49603D03*
X628160Y559743D03*
X612500Y535000D03*
X724900Y488200D03*
X720200D03*
X751500Y48430D03*
X767247Y496827D03*
X800388Y517356D03*
G54D63*
X267250Y652500D03*
X259750Y648625D03*
Y656375D03*
X696100Y489716D03*
X688600Y493591D03*
Y485841D03*
X680250Y489500D03*
X672750Y493375D03*
Y485625D03*
X829970Y61300D03*
X822470Y65175D03*
Y57425D03*
G54D54*
X163189Y669291D03*
G54D81*
X390527Y67190D03*
X386727D03*
X390527Y73790D03*
X386727D03*
G54D138*
X749030Y477405D03*
Y473468D03*
X738614Y475437D03*
G54D129*
X630113Y531937D03*
X624207D03*
Y544149D03*
X630113D03*
G54D72*
X297146Y199016D03*
Y195866D03*
Y192717D03*
X314666Y199016D03*
Y195866D03*
Y192717D03*
X297146Y265158D03*
Y262008D03*
Y258858D03*
Y255709D03*
Y252559D03*
Y249410D03*
Y246260D03*
Y243110D03*
Y239961D03*
Y236811D03*
Y233661D03*
Y230512D03*
Y227362D03*
Y224213D03*
Y221063D03*
Y217913D03*
Y214764D03*
Y211614D03*
Y208465D03*
Y205315D03*
Y202165D03*
X314666Y265158D03*
Y262008D03*
Y258858D03*
Y255709D03*
Y252559D03*
Y249410D03*
Y246260D03*
Y243110D03*
Y239961D03*
Y236811D03*
Y233661D03*
Y230512D03*
Y227362D03*
Y224213D03*
Y221063D03*
Y217913D03*
Y214764D03*
Y211614D03*
Y208465D03*
Y205315D03*
Y202165D03*
X297146Y328150D03*
Y325000D03*
Y321850D03*
Y318701D03*
Y315551D03*
Y312402D03*
Y309252D03*
Y306102D03*
Y302953D03*
Y299803D03*
Y296654D03*
Y293504D03*
Y290354D03*
Y287205D03*
Y284055D03*
Y280906D03*
Y277756D03*
Y274606D03*
Y271457D03*
Y268307D03*
X314666Y328150D03*
Y325000D03*
Y321850D03*
Y318701D03*
Y315551D03*
Y312402D03*
Y309252D03*
Y306102D03*
Y302953D03*
Y299803D03*
Y296654D03*
Y293504D03*
Y290354D03*
Y287205D03*
Y284055D03*
Y280906D03*
Y277756D03*
Y274606D03*
Y271457D03*
Y268307D03*
X297146Y378543D03*
Y375394D03*
Y372244D03*
Y369095D03*
Y365945D03*
Y362795D03*
Y359646D03*
Y356496D03*
Y353347D03*
Y350197D03*
Y347047D03*
Y343898D03*
Y340748D03*
Y337599D03*
Y334449D03*
Y331299D03*
X314666Y378543D03*
Y375394D03*
Y372244D03*
Y369095D03*
Y365945D03*
Y362795D03*
Y359646D03*
Y356496D03*
Y353347D03*
Y350197D03*
Y347047D03*
Y343898D03*
Y340748D03*
Y337599D03*
Y334449D03*
Y331299D03*
G54D90*
X372000Y71900D03*
G54D36*
X49900Y671384D03*
X117700Y515200D03*
X85500Y632700D03*
X81784Y667900D03*
X203650Y633050D03*
X207060Y629620D03*
X170100Y704600D03*
X210520Y629310D03*
X247400Y639400D03*
X225400Y713000D03*
X263000Y675700D03*
X328659Y536059D03*
X317600Y606800D03*
X322100Y641700D03*
X314920Y678920D03*
X311704Y712120D03*
X366699Y201221D03*
X521800Y49800D03*
X559200Y40500D03*
X633800Y337900D03*
X614000Y337300D03*
X645300Y526200D03*
X702460Y481050D03*
X728559Y474298D03*
X676194Y586129D03*
X723676Y587629D03*
X776200Y51200D03*
X786600Y416200D03*
X794500Y497600D03*
X757099Y522966D03*
X826284Y501900D03*
X883100Y221100D03*
G54D18*
X18700Y54650D03*
X209189Y37075D03*
Y383483D03*
X489331Y245605D03*
Y698924D03*
X901000Y21400D03*
X902500Y676000D03*
G54D45*
X140500Y620300D03*
X208000Y520500D03*
X208100Y515200D03*
X202800Y509900D03*
X174100Y628900D03*
X168800Y628400D03*
X159200Y623240D03*
X164130Y625550D03*
X168300Y621900D03*
X158350Y629040D03*
X181540Y644450D03*
X217100Y520300D03*
X238200Y524600D03*
X235562Y541096D03*
X249998Y550219D03*
X246800Y541900D03*
X241100Y541600D03*
X240900Y547300D03*
X235500Y548200D03*
X226168Y618952D03*
X235600Y611800D03*
X368500Y591900D03*
X519900Y103150D03*
X533080Y108300D03*
X520000Y108700D03*
X594000Y151500D03*
X600000D03*
X587300Y151400D03*
X616300D03*
X610900Y151500D03*
X605400Y151400D03*
X622310Y157470D03*
X621600Y151600D03*
X730000Y196800D03*
X724700D03*
X681700Y155600D03*
X678100Y151500D03*
X697400Y155500D03*
X693400Y151700D03*
X689400Y155500D03*
X705300Y155100D03*
X685600Y151400D03*
X701100Y151600D03*
X726000Y322000D03*
X720613Y321539D03*
X693300Y297000D03*
X691200Y306300D03*
X706300Y319900D03*
X696000Y311100D03*
X699000Y290100D03*
X696200Y301700D03*
X713400Y316800D03*
X699300Y306900D03*
X732000Y341400D03*
X732600Y346900D03*
X722500Y341000D03*
X787900Y196700D03*
X793200D03*
X798700D03*
X775600D03*
X780500Y190500D03*
X782500Y196800D03*
X770300Y196700D03*
X758947Y196761D03*
X735500Y196800D03*
X740900Y196750D03*
X752922Y196789D03*
X738586Y340730D03*
X810500Y196700D03*
X804600D03*
G54D27*
X72577Y578589D03*
X69427D03*
X66278D03*
X72577Y581738D03*
X69427D03*
X66278D03*
X72577Y584888D03*
X69427D03*
X66278D03*
X72577Y540794D03*
X69427D03*
X66278D03*
X72577Y543943D03*
X69427D03*
X66278D03*
X72577Y537644D03*
X69427D03*
X66278D03*
X72577Y547093D03*
X69427D03*
X66278D03*
X72577Y550242D03*
X69427D03*
X66278D03*
X72577Y553392D03*
X69427D03*
X66278D03*
X72577Y556542D03*
X69427D03*
X66278D03*
X72577Y559691D03*
X69427D03*
X66278D03*
X72577Y562841D03*
X69427D03*
X66278D03*
X72577Y565990D03*
X69427D03*
X66278D03*
X72577Y569140D03*
X69427D03*
X66278D03*
X72577Y572290D03*
X69427D03*
X66278D03*
X72577Y575439D03*
X69427D03*
X66278D03*
X102700Y507100D03*
X101800Y493000D03*
X91474Y569140D03*
Y572290D03*
Y575439D03*
Y578589D03*
Y581738D03*
Y584888D03*
X88325Y578589D03*
X85175D03*
X88325Y581738D03*
X85175D03*
X88325Y584888D03*
X85175D03*
Y547093D03*
X91474Y540794D03*
X88325D03*
X85175D03*
X91474Y543943D03*
X88325D03*
X85175D03*
X91474Y537644D03*
X88325D03*
X85175D03*
X91474Y547093D03*
X88325D03*
X91474Y550242D03*
X88325D03*
X85175D03*
X91474Y553392D03*
X88325D03*
X85175D03*
X91474Y556542D03*
X88325D03*
X85175D03*
X91474Y559691D03*
X88325D03*
X85175D03*
X91474Y562841D03*
X88325D03*
X85175D03*
X91474Y565990D03*
X88325D03*
X85175D03*
X88325Y569140D03*
X85175D03*
X88325Y572290D03*
X85175D03*
X88325Y575439D03*
X85175D03*
X123500Y613100D03*
X141971Y624700D03*
X105600Y597000D03*
X105400Y601300D03*
X104600Y609900D03*
X105600Y605900D03*
X104600Y614000D03*
X104500Y618800D03*
X116200Y611600D03*
X116023Y607423D03*
X119400Y614100D03*
X116400Y616900D03*
X129903Y634500D03*
X176000Y460200D03*
X183300Y493100D03*
X205447Y487762D03*
X182874Y523590D03*
X165900Y524100D03*
X196200Y482600D03*
X195379Y510158D03*
X154724Y547244D03*
Y550394D03*
Y553543D03*
Y556693D03*
Y559842D03*
Y562992D03*
Y566142D03*
Y569291D03*
Y572441D03*
Y575590D03*
Y578740D03*
Y581890D03*
Y585039D03*
Y588189D03*
Y591338D03*
X157874Y547244D03*
Y550394D03*
Y553543D03*
Y556693D03*
Y559842D03*
Y562992D03*
Y566142D03*
Y569291D03*
Y572441D03*
Y575590D03*
Y578740D03*
Y581890D03*
Y585039D03*
Y588189D03*
Y591338D03*
X161023Y547244D03*
Y550394D03*
Y553543D03*
Y556693D03*
Y559842D03*
Y562992D03*
Y566142D03*
Y569291D03*
Y572441D03*
Y575590D03*
Y578740D03*
Y581890D03*
Y585039D03*
Y588189D03*
Y591338D03*
X164173Y537795D03*
Y540945D03*
Y544094D03*
Y547244D03*
Y550394D03*
Y553543D03*
Y556693D03*
Y559842D03*
Y562992D03*
Y566142D03*
Y569291D03*
Y572441D03*
Y575590D03*
Y578740D03*
Y581890D03*
Y585039D03*
Y588189D03*
Y591338D03*
X167323Y537795D03*
Y540945D03*
Y544094D03*
Y547244D03*
Y550394D03*
Y553543D03*
Y556693D03*
Y559842D03*
Y562992D03*
Y566142D03*
Y569291D03*
Y572441D03*
Y575590D03*
Y578740D03*
Y581890D03*
Y585039D03*
Y588189D03*
Y591338D03*
X170472Y537795D03*
Y540945D03*
Y544094D03*
Y547244D03*
Y550394D03*
Y553543D03*
Y556693D03*
Y559842D03*
Y562992D03*
Y566142D03*
Y569291D03*
Y572441D03*
Y575590D03*
Y578740D03*
Y581890D03*
Y585039D03*
Y588189D03*
Y591338D03*
X173622Y537795D03*
Y540945D03*
Y544094D03*
Y547244D03*
Y550394D03*
Y553543D03*
Y556693D03*
Y559842D03*
Y562992D03*
Y566142D03*
Y569291D03*
Y572441D03*
Y575590D03*
Y578740D03*
Y581890D03*
Y585039D03*
Y588189D03*
Y591338D03*
X176771Y537795D03*
Y540945D03*
Y544094D03*
Y547244D03*
Y550394D03*
Y553543D03*
Y556693D03*
Y585039D03*
Y588189D03*
Y591338D03*
X179921Y537795D03*
Y540945D03*
Y544094D03*
Y547244D03*
Y550394D03*
Y553543D03*
Y556693D03*
Y562992D03*
Y566142D03*
Y569291D03*
Y572441D03*
Y575590D03*
Y578740D03*
Y585039D03*
Y588189D03*
Y591338D03*
X183071Y537795D03*
Y540945D03*
Y544094D03*
Y547244D03*
Y550394D03*
Y553543D03*
Y556693D03*
Y562992D03*
Y566142D03*
Y569291D03*
Y572441D03*
Y575590D03*
Y578740D03*
Y585039D03*
Y588189D03*
Y591338D03*
X186220Y537795D03*
Y540945D03*
Y544094D03*
Y547244D03*
Y550394D03*
Y553543D03*
Y556693D03*
Y562992D03*
Y566142D03*
Y569291D03*
Y572441D03*
Y575590D03*
Y578740D03*
Y585039D03*
Y588189D03*
Y591338D03*
X189370Y537795D03*
Y540945D03*
Y544094D03*
Y547244D03*
Y550394D03*
Y553543D03*
Y556693D03*
Y562992D03*
Y566142D03*
Y569291D03*
Y572441D03*
Y575590D03*
Y578740D03*
Y585039D03*
Y588189D03*
Y591338D03*
X192519Y537795D03*
Y540945D03*
Y544094D03*
Y547244D03*
Y550394D03*
Y553543D03*
Y556693D03*
Y562992D03*
Y566142D03*
Y569291D03*
Y572441D03*
Y575590D03*
Y578740D03*
Y585039D03*
Y588189D03*
Y591338D03*
X195669Y537795D03*
Y540945D03*
Y544094D03*
Y547244D03*
Y550394D03*
Y553543D03*
Y556693D03*
Y562992D03*
Y566142D03*
Y569291D03*
Y572441D03*
Y575590D03*
Y578740D03*
Y585039D03*
Y588189D03*
Y591338D03*
X198819Y537795D03*
Y540945D03*
Y544094D03*
Y547244D03*
Y550394D03*
Y553543D03*
Y556693D03*
Y585039D03*
Y588189D03*
Y591338D03*
X201968Y537795D03*
Y540945D03*
Y544094D03*
Y547244D03*
Y550394D03*
Y553543D03*
Y556693D03*
Y559842D03*
Y562992D03*
Y566142D03*
Y569291D03*
Y572441D03*
Y575590D03*
Y578740D03*
Y581890D03*
Y585039D03*
Y588189D03*
Y591338D03*
X205118Y537795D03*
Y540945D03*
Y544094D03*
Y547244D03*
Y550394D03*
Y553543D03*
Y556693D03*
Y559842D03*
Y562992D03*
Y566142D03*
Y569291D03*
Y572441D03*
Y575590D03*
Y578740D03*
Y581890D03*
Y585039D03*
Y588189D03*
Y591338D03*
X208267Y537795D03*
Y540945D03*
Y544094D03*
Y547244D03*
Y550394D03*
Y553543D03*
Y556693D03*
Y559842D03*
Y562992D03*
Y566142D03*
Y569291D03*
Y572441D03*
Y575590D03*
Y578740D03*
Y581890D03*
Y585039D03*
Y588189D03*
Y591338D03*
X154724Y594488D03*
X157874D03*
X161023D03*
X164173D03*
Y597638D03*
Y600787D03*
Y603937D03*
X167323Y594488D03*
Y597638D03*
Y600787D03*
Y603937D03*
X170472Y594488D03*
Y597638D03*
Y600787D03*
Y603937D03*
X173622Y594488D03*
Y597638D03*
Y600787D03*
Y603937D03*
X176771Y594488D03*
Y597638D03*
Y600787D03*
Y603937D03*
X179921Y594488D03*
Y597638D03*
Y600787D03*
Y603937D03*
X183071Y594488D03*
Y597638D03*
Y600787D03*
Y603937D03*
X186220Y594488D03*
Y597638D03*
Y600787D03*
Y603937D03*
X189370Y594488D03*
Y597638D03*
Y600787D03*
Y603937D03*
X192519Y594488D03*
Y597638D03*
Y600787D03*
Y603937D03*
X195669Y594488D03*
Y597638D03*
Y600787D03*
Y603937D03*
X198819Y594488D03*
Y597638D03*
Y600787D03*
Y603937D03*
X201968Y594488D03*
Y597638D03*
Y600787D03*
Y603937D03*
X205118Y594488D03*
Y597638D03*
Y600787D03*
Y603937D03*
X208267Y594488D03*
Y597638D03*
Y600787D03*
Y603937D03*
X194490Y645390D03*
X151550Y629800D03*
X146800Y629900D03*
X204150Y645180D03*
X199600Y650100D03*
X192960Y628510D03*
X187900Y628500D03*
X150849Y710215D03*
X254500Y509600D03*
X228700Y490717D03*
X230700Y486658D03*
X249640Y495080D03*
X234700Y490900D03*
X211417Y537795D03*
Y540945D03*
Y544094D03*
Y547244D03*
Y550394D03*
Y553543D03*
Y556693D03*
Y559842D03*
Y562992D03*
Y566142D03*
Y569291D03*
Y572441D03*
Y575590D03*
Y578740D03*
Y581890D03*
Y585039D03*
Y588189D03*
Y591338D03*
X214567Y547244D03*
Y550394D03*
Y553543D03*
Y556693D03*
Y559842D03*
Y562992D03*
Y566142D03*
Y569291D03*
Y572441D03*
Y575590D03*
Y578740D03*
Y581890D03*
Y585039D03*
Y588189D03*
Y591338D03*
X217716Y547244D03*
Y550394D03*
Y553543D03*
Y556693D03*
Y559842D03*
Y562992D03*
Y566142D03*
Y569291D03*
Y572441D03*
Y575590D03*
Y578740D03*
Y581890D03*
Y585039D03*
Y588189D03*
Y591338D03*
X220866Y547244D03*
Y550394D03*
Y553543D03*
Y556693D03*
Y559842D03*
Y562992D03*
Y566142D03*
Y569291D03*
Y572441D03*
Y575590D03*
Y578740D03*
Y581890D03*
Y585039D03*
Y588189D03*
Y591338D03*
X254905Y555761D03*
X211417Y594488D03*
Y597638D03*
Y600787D03*
Y603937D03*
X214567Y594488D03*
X217716D03*
X220866D03*
X286797Y516522D03*
X292100Y516000D03*
X297400Y517981D03*
X278400Y463300D03*
X333800Y534830D03*
X329840Y572710D03*
X325475Y572818D03*
X298000Y561000D03*
X328580Y568120D03*
X320954Y572631D03*
X337346Y545100D03*
X308200Y593153D03*
X325300Y648700D03*
X330400Y644300D03*
X327250Y701500D03*
X390229Y508189D03*
X373800Y503000D03*
X378267Y496100D03*
X344163Y553395D03*
X364964Y588771D03*
X380387Y685261D03*
X392500Y673500D03*
X564500Y64100D03*
X586155Y393023D03*
X713386Y264173D03*
X716535D03*
X719685D03*
X722835D03*
X725984D03*
X729134D03*
X732283D03*
X713386Y261023D03*
X716535D03*
X719685D03*
X722835D03*
X725984D03*
X729134D03*
X732283D03*
X713386Y257874D03*
X716535D03*
X719685D03*
X722835D03*
X725984D03*
X729134D03*
X732283D03*
X713386Y254724D03*
X716535D03*
X719685D03*
X722835D03*
X725984D03*
X729134D03*
X732283D03*
X713386Y251575D03*
X716535D03*
X719685D03*
X722835D03*
X725984D03*
X729134D03*
X732283D03*
X713386Y248425D03*
X716535D03*
X719685D03*
X722835D03*
X725984D03*
X729134D03*
X732283D03*
X713386Y245275D03*
X716535D03*
X719685D03*
X722835D03*
X725984D03*
X729134D03*
X732283D03*
X713386Y242126D03*
X716535D03*
X719685D03*
X722835D03*
X725984D03*
X729134D03*
X732283D03*
X713386Y238976D03*
X716535D03*
X719685D03*
X722835D03*
X725984D03*
X729134D03*
X732283D03*
X713386Y235827D03*
X716535D03*
X719685D03*
X722835D03*
X725984D03*
X729134D03*
X732283D03*
X713386Y232677D03*
X716535D03*
X719685D03*
X722835D03*
X725984D03*
X729134D03*
X732283D03*
X713386Y229527D03*
X716535D03*
X719685D03*
X722835D03*
X725984D03*
X729134D03*
X732283D03*
X713386Y226378D03*
X716535D03*
X719685D03*
X722835D03*
X725984D03*
X729134D03*
X732283D03*
X713386Y223228D03*
X716535D03*
X719685D03*
X722835D03*
X725984D03*
X729134D03*
X732283D03*
X713386Y220079D03*
X716535D03*
X719685D03*
X722835D03*
X725984D03*
X729134D03*
X732283D03*
X722835Y216929D03*
X725984D03*
X729134D03*
X732283D03*
X722835Y213779D03*
X725984D03*
X729134D03*
X732283D03*
X722835Y210630D03*
X725984D03*
X729134D03*
X732283D03*
X722835Y301968D03*
X725984D03*
X729134D03*
X732283D03*
X722835Y298819D03*
X725984D03*
X729134D03*
X732283D03*
X722835Y295669D03*
X725984D03*
X729134D03*
X732283D03*
X713386Y292519D03*
X716535D03*
X719685D03*
X722835D03*
X725984D03*
X729134D03*
X732283D03*
X713386Y289370D03*
X716535D03*
X719685D03*
X722835D03*
X725984D03*
X729134D03*
X732283D03*
X713386Y286220D03*
X716535D03*
X719685D03*
X722835D03*
X725984D03*
X729134D03*
X732283D03*
X713386Y283071D03*
X716535D03*
X719685D03*
X722835D03*
X725984D03*
X729134D03*
X732283D03*
X713386Y279921D03*
X716535D03*
X719685D03*
X722835D03*
X725984D03*
X729134D03*
X732283D03*
X713386Y276771D03*
X716535D03*
X719685D03*
X722835D03*
X725984D03*
X729134D03*
X732283D03*
X713386Y273622D03*
X716535D03*
X719685D03*
X722835D03*
X725984D03*
X729134D03*
X732283D03*
X713386Y270472D03*
X716535D03*
X719685D03*
X722835D03*
X725984D03*
X729134D03*
X732283D03*
X713386Y267323D03*
X716535D03*
X719685D03*
X722835D03*
X725984D03*
X729134D03*
X732283D03*
X735433Y264173D03*
X738583D03*
X741732D03*
X744882D03*
X748031D03*
X751181D03*
X754331D03*
X757480D03*
X760630D03*
X763779D03*
X766929D03*
X770079D03*
X773228D03*
X776378D03*
X779527D03*
X782677D03*
X785827D03*
X788976D03*
X792126D03*
X795275D03*
X798425D03*
X735433Y261023D03*
X738583D03*
X741732D03*
X744882D03*
X748031D03*
X751181D03*
X754331D03*
X757480D03*
X760630D03*
X763779D03*
X766929D03*
X770079D03*
X773228D03*
X776378D03*
X779527D03*
X782677D03*
X785827D03*
X788976D03*
X792126D03*
X795275D03*
X798425D03*
X735433Y257874D03*
X738583D03*
X741732D03*
X744882D03*
X748031D03*
X751181D03*
X754331D03*
X757480D03*
X760630D03*
X763779D03*
X766929D03*
X770079D03*
X773228D03*
X776378D03*
X779527D03*
X782677D03*
X785827D03*
X788976D03*
X792126D03*
X795275D03*
X798425D03*
X735433Y254724D03*
X738583D03*
X741732D03*
X744882D03*
X748031D03*
X751181D03*
X754331D03*
X757480D03*
X760630D03*
X763779D03*
X766929D03*
X770079D03*
X773228D03*
X776378D03*
X779527D03*
X782677D03*
X785827D03*
X788976D03*
X792126D03*
X795275D03*
X798425D03*
X735433Y251575D03*
X738583D03*
X741732D03*
X744882D03*
X748031D03*
X751181D03*
X754331D03*
X757480D03*
X760630D03*
X763779D03*
X766929D03*
X770079D03*
X773228D03*
X776378D03*
X779527D03*
X782677D03*
X785827D03*
X788976D03*
X792126D03*
X795275D03*
X798425D03*
X735433Y248425D03*
X738583D03*
X741732D03*
X744882D03*
X748031D03*
X751181D03*
X754331D03*
X757480D03*
X760630D03*
X763779D03*
X766929D03*
X770079D03*
X773228D03*
X776378D03*
X779527D03*
X782677D03*
X785827D03*
X788976D03*
X792126D03*
X795275D03*
X798425D03*
X735433Y245275D03*
X738583D03*
X741732D03*
X744882D03*
X748031D03*
X751181D03*
X754331D03*
X757480D03*
X760630D03*
X763779D03*
X766929D03*
X770079D03*
X773228D03*
X776378D03*
X779527D03*
X782677D03*
X785827D03*
X788976D03*
X792126D03*
X795275D03*
X798425D03*
X735433Y242126D03*
X738583D03*
X741732D03*
X744882D03*
X748031D03*
X751181D03*
X754331D03*
X757480D03*
X760630D03*
X763779D03*
X766929D03*
X770079D03*
X773228D03*
X776378D03*
X779527D03*
X782677D03*
X785827D03*
X788976D03*
X792126D03*
X795275D03*
X798425D03*
X735433Y238976D03*
X738583D03*
X741732D03*
X744882D03*
X748031D03*
X751181D03*
X754331D03*
X757480D03*
X760630D03*
X763779D03*
X766929D03*
X770079D03*
X773228D03*
X776378D03*
X779527D03*
X782677D03*
X785827D03*
X788976D03*
X792126D03*
X795275D03*
X798425D03*
X735433Y235827D03*
X738583D03*
X741732D03*
X744882D03*
X748031D03*
X751181D03*
X754331D03*
X757480D03*
X760630D03*
X763779D03*
X766929D03*
X770079D03*
X773228D03*
X776378D03*
X779527D03*
X782677D03*
X785827D03*
X788976D03*
X792126D03*
X795275D03*
X798425D03*
X735433Y232677D03*
X738583D03*
X741732D03*
X744882D03*
X748031D03*
X751181D03*
X754331D03*
X757480D03*
X760630D03*
X763779D03*
X766929D03*
X770079D03*
X773228D03*
X776378D03*
X779527D03*
X782677D03*
X785827D03*
X788976D03*
X792126D03*
X795275D03*
X798425D03*
X735433Y229527D03*
X738583D03*
X741732D03*
X744882D03*
X748031D03*
X751181D03*
X754331D03*
X757480D03*
X760630D03*
X763779D03*
X766929D03*
X770079D03*
X773228D03*
X776378D03*
X779527D03*
X782677D03*
X785827D03*
X788976D03*
X792126D03*
X795275D03*
X798425D03*
X735433Y226378D03*
X738583D03*
X741732D03*
X744882D03*
X748031D03*
X751181D03*
X754331D03*
X757480D03*
X760630D03*
X763779D03*
X766929D03*
X770079D03*
X773228D03*
X776378D03*
X779527D03*
X782677D03*
X785827D03*
X788976D03*
X792126D03*
X795275D03*
X798425D03*
X735433Y223228D03*
X738583D03*
X741732D03*
X744882D03*
X748031D03*
X751181D03*
X754331D03*
X757480D03*
X760630D03*
X763779D03*
X766929D03*
X770079D03*
X773228D03*
X776378D03*
X779527D03*
X782677D03*
X785827D03*
X788976D03*
X792126D03*
X795275D03*
X798425D03*
X735433Y220079D03*
X738583D03*
X741732D03*
X744882D03*
X748031D03*
X751181D03*
X754331D03*
X757480D03*
X760630D03*
X763779D03*
X766929D03*
X770079D03*
X773228D03*
X776378D03*
X779527D03*
X782677D03*
X785827D03*
X788976D03*
X792126D03*
X795275D03*
X798425D03*
X735433Y216929D03*
X738583D03*
X741732D03*
X744882D03*
X748031D03*
X751181D03*
X754331D03*
X757480D03*
X760630D03*
X763779D03*
X766929D03*
X770079D03*
X773228D03*
X776378D03*
X779527D03*
X782677D03*
X785827D03*
X788976D03*
X792126D03*
X795275D03*
X735433Y213779D03*
X738583D03*
X741732D03*
X744882D03*
X748031D03*
X751181D03*
X754331D03*
X757480D03*
X760630D03*
X763779D03*
X766929D03*
X770079D03*
X773228D03*
X776378D03*
X779527D03*
X782677D03*
X785827D03*
X788976D03*
X792126D03*
X795275D03*
X735433Y210630D03*
X738583D03*
X741732D03*
X744882D03*
X748031D03*
X751181D03*
X754331D03*
X757480D03*
X760630D03*
X763779D03*
X766929D03*
X770079D03*
X773228D03*
X776378D03*
X779527D03*
X782677D03*
X785827D03*
X788976D03*
X792126D03*
X795275D03*
X768579Y203964D03*
X735433Y301968D03*
X738583D03*
X741732D03*
X744882D03*
X748031D03*
X751181D03*
X754331D03*
X757480D03*
X760630D03*
X763779D03*
X766929D03*
X770079D03*
X773228D03*
X776378D03*
X779527D03*
X782677D03*
X785827D03*
X788976D03*
X792126D03*
X795275D03*
X735433Y298819D03*
X738583D03*
X741732D03*
X744882D03*
X748031D03*
X751181D03*
X754331D03*
X757480D03*
X760630D03*
X763779D03*
X766929D03*
X770079D03*
X773228D03*
X776378D03*
X779527D03*
X782677D03*
X785827D03*
X788976D03*
X792126D03*
X795275D03*
X735433Y295669D03*
X738583D03*
X741732D03*
X744882D03*
X748031D03*
X751181D03*
X754331D03*
X757480D03*
X760630D03*
X763779D03*
X766929D03*
X770079D03*
X773228D03*
X776378D03*
X779527D03*
X782677D03*
X785827D03*
X788976D03*
X792126D03*
X795275D03*
X735433Y292519D03*
X738583D03*
X741732D03*
X744882D03*
X748031D03*
X751181D03*
X754331D03*
X757480D03*
X760630D03*
X763779D03*
X766929D03*
X770079D03*
X773228D03*
X776378D03*
X779527D03*
X782677D03*
X785827D03*
X788976D03*
X792126D03*
X795275D03*
X798425D03*
X735433Y289370D03*
X738583D03*
X741732D03*
X744882D03*
X748031D03*
X751181D03*
X754331D03*
X757480D03*
X760630D03*
X763779D03*
X766929D03*
X770079D03*
X773228D03*
X776378D03*
X779527D03*
X782677D03*
X785827D03*
X788976D03*
X792126D03*
X795275D03*
X798425D03*
X735433Y286220D03*
X738583D03*
X741732D03*
X744882D03*
X748031D03*
X751181D03*
X754331D03*
X757480D03*
X760630D03*
X763779D03*
X766929D03*
X770079D03*
X773228D03*
X776378D03*
X779527D03*
X782677D03*
X785827D03*
X788976D03*
X792126D03*
X795275D03*
X798425D03*
X735433Y283071D03*
X738583D03*
X741732D03*
X744882D03*
X748031D03*
X751181D03*
X754331D03*
X757480D03*
X760630D03*
X763779D03*
X766929D03*
X770079D03*
X773228D03*
X776378D03*
X779527D03*
X782677D03*
X785827D03*
X788976D03*
X792126D03*
X795275D03*
X798425D03*
X735433Y279921D03*
X738583D03*
X741732D03*
X744882D03*
X748031D03*
X751181D03*
X754331D03*
X757480D03*
X760630D03*
X763779D03*
X766929D03*
X770079D03*
X773228D03*
X776378D03*
X779527D03*
X782677D03*
X785827D03*
X788976D03*
X792126D03*
X795275D03*
X798425D03*
X735433Y276771D03*
X738583D03*
X741732D03*
X744882D03*
X748031D03*
X751181D03*
X754331D03*
X757480D03*
X760630D03*
X763779D03*
X766929D03*
X770079D03*
X773228D03*
X776378D03*
X779527D03*
X782677D03*
X785827D03*
X788976D03*
X792126D03*
X795275D03*
X798425D03*
X735433Y273622D03*
X738583D03*
X741732D03*
X744882D03*
X748031D03*
X751181D03*
X754331D03*
X757480D03*
X760630D03*
X763779D03*
X766929D03*
X770079D03*
X773228D03*
X776378D03*
X779527D03*
X782677D03*
X785827D03*
X788976D03*
X792126D03*
X795275D03*
X798425D03*
X735433Y270472D03*
X738583D03*
X741732D03*
X744882D03*
X748031D03*
X751181D03*
X754331D03*
X757480D03*
X760630D03*
X763779D03*
X766929D03*
X770079D03*
X773228D03*
X776378D03*
X779527D03*
X782677D03*
X785827D03*
X788976D03*
X792126D03*
X795275D03*
X798425D03*
X735433Y267323D03*
X738583D03*
X741732D03*
X744882D03*
X748031D03*
X751181D03*
X754331D03*
X757480D03*
X760630D03*
X763779D03*
X766929D03*
X770079D03*
X773228D03*
X776378D03*
X779527D03*
X782677D03*
X785827D03*
X788976D03*
X792126D03*
X795275D03*
X798425D03*
X735300Y401957D03*
X801575Y264173D03*
X804724D03*
X801575Y261023D03*
X804724D03*
X801575Y257874D03*
X804724D03*
X801575Y254724D03*
X804724D03*
X801575Y251575D03*
X804724D03*
X801575Y248425D03*
X804724D03*
X801575Y245275D03*
X804724D03*
X801575Y242126D03*
X804724D03*
X801575Y238976D03*
X804724D03*
X801575Y235827D03*
X804724D03*
X801575Y232677D03*
X804724D03*
X801575Y229527D03*
X804724D03*
X801575Y226378D03*
X804724D03*
X801575Y223228D03*
X804724D03*
X801575Y220079D03*
X804724D03*
X801575Y292519D03*
X804724D03*
X801575Y289370D03*
X804724D03*
X801575Y286220D03*
X804724D03*
X801575Y283071D03*
X804724D03*
X801575Y279921D03*
X804724D03*
X801575Y276771D03*
X804724D03*
X801575Y273622D03*
X804724D03*
X801575Y270472D03*
X804724D03*
X801575Y267323D03*
X804724D03*
G54D55*
X153549Y687715D03*
X434500Y52457D03*
Y42657D03*
Y47557D03*
X629860Y521543D03*
X703400Y558300D03*
X795224Y42000D03*
X821224D03*
G54D37*
X65714Y665850D03*
X306300Y638600D03*
X295634Y710070D03*
X810214Y499850D03*
G54D91*
X356611Y200364D03*
X351611D03*
X346611D03*
X341611D03*
Y220364D03*
X346611D03*
X351611D03*
X356611D03*
G54D19*
X34070Y48070D03*
Y54070D03*
X93640Y54860D03*
Y60860D03*
G54D82*
X371768Y53823D03*
Y49223D03*
X371594Y84695D03*
Y80095D03*
G54D64*
X244750Y652500D03*
X252250Y656375D03*
Y648625D03*
X244750Y666500D03*
X252250Y662625D03*
Y670375D03*
X359976Y183681D03*
X367476Y179806D03*
Y187556D03*
X491740Y63670D03*
X499240Y67545D03*
Y59795D03*
X683000Y473384D03*
X690500Y469509D03*
Y477259D03*
G54D73*
X305906Y182874D03*
G54D28*
X50050Y529400D03*
X55895Y643491D03*
X73265Y647355D03*
X49300Y656600D03*
X34300Y677500D03*
X76264Y685964D03*
X46043Y679557D03*
X88900Y498700D03*
X103800Y570500D03*
X126870Y598031D03*
X139959Y606009D03*
X139971Y614874D03*
X112850Y641488D03*
X128793Y613483D03*
X139728Y596666D03*
X83450Y646620D03*
X144550Y618316D03*
X123534Y593743D03*
X117000Y597000D03*
X115006Y625751D03*
X139679Y601454D03*
X144000Y645600D03*
X127900Y643420D03*
X134700Y643441D03*
X127597Y693231D03*
X117767Y702633D03*
X121501Y699049D03*
X106400Y722900D03*
X138653Y739871D03*
X144249Y733200D03*
X199755Y524755D03*
X194803Y525639D03*
X187000Y524214D03*
X188584Y528105D03*
X177017Y526942D03*
X172800Y524100D03*
X170200Y527400D03*
X182000Y527362D03*
X162800Y527600D03*
X153812Y526926D03*
X158100Y524100D03*
X210000Y510000D03*
X204752Y524566D03*
X145100Y539800D03*
X145012Y544801D03*
X145100Y549900D03*
X205000Y614500D03*
X194200Y613700D03*
X189185Y617400D03*
X185085Y613700D03*
X182200Y617100D03*
X178800Y614100D03*
X175040Y616035D03*
X163300Y629800D03*
X197315Y617778D03*
X201449Y619094D03*
X149250Y618050D03*
X153901Y617796D03*
X158898Y617993D03*
X160200Y639600D03*
X156238Y643866D03*
X160249Y699165D03*
X144662Y697593D03*
X269600Y523350D03*
X225300Y527900D03*
X231800Y522500D03*
X221800Y523700D03*
X221187Y516937D03*
X213487Y524273D03*
X272723Y540752D03*
X230940Y565901D03*
X236700Y562800D03*
X235339Y568279D03*
X235721Y575076D03*
X236210Y584419D03*
X232763Y579124D03*
X231200Y559800D03*
X267200Y548200D03*
X259800Y528926D03*
X257161Y559865D03*
X250700Y530500D03*
X241300Y585000D03*
X231204Y529404D03*
X267200Y576400D03*
X240800Y528500D03*
X252590Y538010D03*
X211600Y614400D03*
X216000Y622450D03*
X223593Y634091D03*
X220400Y654600D03*
X214500Y626500D03*
X220614Y616544D03*
X233300Y618300D03*
X238000Y617896D03*
X237000Y597400D03*
X275500Y652348D03*
X240300Y613737D03*
X238950Y651600D03*
X252492Y643414D03*
X264683Y638810D03*
X273467Y657050D03*
X248600Y699300D03*
X256900Y699715D03*
X275349Y723500D03*
X256666Y716225D03*
X271240Y680097D03*
X267350Y710224D03*
X247400Y679150D03*
X221987Y728528D03*
X222306Y737851D03*
X338882Y248674D03*
X340500Y236600D03*
X338982Y243274D03*
X338751Y268585D03*
X339182Y273077D03*
X289500Y451900D03*
X337600Y494968D03*
X318778Y510778D03*
X301620Y515600D03*
X287615Y524997D03*
X340800Y504200D03*
X287271Y545971D03*
X287200Y553300D03*
X306364Y574464D03*
X307519Y584195D03*
X307385Y559544D03*
X307187Y566066D03*
X303091Y568720D03*
X301365Y573221D03*
X298308Y530131D03*
X281158Y538858D03*
X309417Y589500D03*
X323956Y539616D03*
X299294Y542868D03*
X322511Y544355D03*
X320031Y535663D03*
X301216Y535004D03*
X299200Y597400D03*
X290399Y656015D03*
X289917Y649778D03*
X301700Y608000D03*
X314390Y620830D03*
X285988Y637449D03*
X281300Y670200D03*
X282600Y674600D03*
X286500Y693500D03*
X309090Y690532D03*
X276325Y705863D03*
X316000Y671850D03*
X339731Y682730D03*
X301054Y666724D03*
X340583Y670807D03*
X283080Y730387D03*
X374014Y188823D03*
X353762Y181744D03*
X344388Y179571D03*
X362727Y192756D03*
X352017Y263432D03*
X383140Y367158D03*
X360446Y358846D03*
X361176Y379610D03*
X354850Y376362D03*
X369300Y362600D03*
X383900Y422100D03*
X390999Y461382D03*
X352700Y498400D03*
X360400Y470400D03*
X395928Y482925D03*
X377644Y491967D03*
X343000Y492100D03*
X344700Y522600D03*
X376700Y480300D03*
X368543Y479991D03*
X360374Y486117D03*
X352490Y515908D03*
X387561Y540889D03*
X355400Y593400D03*
X372700Y593600D03*
X379628Y589070D03*
X375771Y590734D03*
X383622Y590370D03*
X384746Y547941D03*
X349700Y577400D03*
X386835Y563988D03*
X351030Y536681D03*
X345443Y531460D03*
X365270Y580800D03*
X349334Y557789D03*
X349005Y549206D03*
X385845Y614925D03*
X383127Y595147D03*
X383271Y605000D03*
X388300Y632700D03*
X383168Y626894D03*
X346485Y676801D03*
X383885Y684055D03*
X381888Y678912D03*
X381377Y672923D03*
X380900Y692940D03*
X451500Y28000D03*
X451800Y23000D03*
X467800Y58000D03*
X448859Y42351D03*
X452293Y50940D03*
X460024Y18801D03*
X450900Y33300D03*
X458662Y53326D03*
X470599Y71247D03*
X469653Y88700D03*
X445163Y102450D03*
X456430Y87000D03*
X516600Y49650D03*
X517825Y54994D03*
X521155Y19621D03*
X497990Y54540D03*
X512542Y19091D03*
X473100Y58000D03*
X483235Y36335D03*
X484414Y26637D03*
X476305Y53965D03*
X484965Y63428D03*
X485104Y21491D03*
X481831Y17711D03*
X498150Y26850D03*
X489730Y77724D03*
X494171Y73533D03*
X475310Y89843D03*
X565100Y60400D03*
X551200Y47300D03*
X564100Y44203D03*
X581476Y43046D03*
X549650Y67500D03*
X582090Y58780D03*
X574759Y68489D03*
X555327Y81900D03*
X588676Y373300D03*
X602860Y522543D03*
X640600Y151600D03*
X665500Y201900D03*
X607400Y299100D03*
X657500Y281500D03*
X648000Y281300D03*
X639878Y348571D03*
X618900Y338200D03*
X620139Y380400D03*
X620111Y367921D03*
X608500Y343300D03*
X612466Y368519D03*
X653449Y360181D03*
X632220Y393520D03*
X640960Y377294D03*
X643200Y366300D03*
X603597Y335950D03*
X614022Y382345D03*
X626262Y377540D03*
X655800Y400550D03*
X640891Y414908D03*
X632180Y401800D03*
X635480Y526130D03*
X621108Y520852D03*
X640160Y517269D03*
X647359Y560063D03*
X607676Y540800D03*
X625398Y550500D03*
X634384Y550513D03*
X623327Y559229D03*
X603831Y548331D03*
X639500Y540500D03*
X639300Y532700D03*
X641380Y693090D03*
X647413Y697494D03*
X720878Y180410D03*
X717700Y196400D03*
X710403Y197200D03*
X706357Y180801D03*
X690000Y249500D03*
X690094Y243050D03*
X699145Y258217D03*
X704000Y244800D03*
X694500Y254517D03*
X704508Y233964D03*
X703452Y200958D03*
X694150Y267984D03*
X693668Y278378D03*
X689809Y290474D03*
X703130Y268891D03*
X693300Y273000D03*
X718427Y358980D03*
X709008Y354239D03*
X728038Y336182D03*
X733036Y351439D03*
X675130Y381713D03*
X714200Y445400D03*
X703617Y431443D03*
X683048Y443658D03*
X726211Y483619D03*
X729365Y488535D03*
X696100Y499100D03*
X696500Y465373D03*
X676418Y475383D03*
X681639Y499750D03*
X675300Y499000D03*
X697095Y480132D03*
X729346Y573866D03*
X718551Y555953D03*
X669294Y579571D03*
X706600Y546800D03*
X714777Y561129D03*
X717314Y587242D03*
X714978Y547961D03*
X693500Y554300D03*
X693484Y654328D03*
X733872Y629500D03*
X711081Y595223D03*
X723415Y621166D03*
X720300Y615300D03*
X693405Y676551D03*
X681740Y705064D03*
X752331Y61071D03*
X777666Y43729D03*
X786200Y60535D03*
X766542Y44076D03*
X761600Y68300D03*
X797500Y48500D03*
X783350Y80050D03*
X757100Y113000D03*
X766260Y92788D03*
X776200Y93050D03*
X789000Y100400D03*
X776300Y110100D03*
X778760Y123150D03*
X745300Y196300D03*
X765800Y196847D03*
X746891Y200751D03*
X755729Y201712D03*
X761780Y201451D03*
X741500Y201840D03*
X782693Y431308D03*
X744806Y495350D03*
X758100Y478184D03*
X744018Y516886D03*
X754462Y496762D03*
X771200Y492800D03*
X761200Y511300D03*
X739900Y505700D03*
X758901Y488563D03*
X753519Y508069D03*
X767300Y473700D03*
X795922Y518640D03*
X790200Y514000D03*
X793700Y493400D03*
X784500Y518694D03*
X736394Y593579D03*
X754775Y538079D03*
X790459Y538770D03*
X777100Y531200D03*
X814900Y61800D03*
X809000Y62000D03*
X824200Y48300D03*
X836400Y61300D03*
X858820Y232979D03*
X827988Y238779D03*
X851700Y382900D03*
X857664Y395138D03*
X822958Y393800D03*
X843619Y378326D03*
X856463Y399163D03*
X822900Y399400D03*
X823256Y406365D03*
X810341Y398947D03*
X813974Y404934D03*
X831489Y510582D03*
X800389Y482153D03*
X819036Y481398D03*
X892850Y313349D03*
X881200Y316000D03*
X887703Y300225D03*
X867602Y368048D03*
G54D46*
X135522Y628682D03*
X83000Y734600D03*
X252107Y516929D03*
X689237Y325511D03*
X838300Y36700D03*
X820896Y207364D03*
X888800Y696900D03*
G54D139*
X741114Y479374D03*
G54D29*
X64884Y643900D03*
X148700Y691600D03*
X204286Y698355D03*
X146649Y740015D03*
X275600Y715100D03*
X298400Y524750D03*
X302919Y553653D03*
X294300Y543000D03*
X305670Y612350D03*
X285460Y644250D03*
X294804Y688120D03*
X380800Y543200D03*
X362586Y639880D03*
X353830Y702620D03*
X446135Y34357D03*
X630322Y368128D03*
X613710Y521543D03*
X620300Y467000D03*
X625460Y554943D03*
X642900Y557500D03*
X744630Y452700D03*
X818034Y389702D03*
X809500Y477200D03*
G54D92*
X368412Y232724D03*
X354572D03*
G54D65*
X263491Y692574D03*
X260931D03*
X258371D03*
Y686074D03*
X263491D03*
X251091Y692774D03*
X248531D03*
X245971D03*
Y686274D03*
X251091D03*
X271240Y686350D03*
X273800D03*
X271240Y692850D03*
X276360Y686350D03*
Y692850D03*
X369095Y217923D03*
X366535D03*
X363975D03*
Y211423D03*
X369095D03*
X366340Y487050D03*
X368900D03*
X371460D03*
Y493550D03*
X366340D03*
X557660Y60130D03*
X555100D03*
X552540D03*
Y53630D03*
X557660D03*
X707944Y470930D03*
X705384D03*
X702824D03*
Y464430D03*
X707944D03*
X783860Y47062D03*
X786420D03*
X788980D03*
Y53562D03*
X783860D03*
X762740Y99750D03*
X765300D03*
X767860D03*
Y106250D03*
X762740D03*
X772060Y78750D03*
X769500D03*
X766940D03*
Y72250D03*
X772060D03*
G54D38*
X55971Y660732D03*
Y663291D03*
Y665850D03*
Y668409D03*
Y670968D03*
X75457D03*
Y668409D03*
Y665850D03*
Y663291D03*
Y660732D03*
X296557Y633482D03*
Y636041D03*
Y638600D03*
Y641159D03*
Y643718D03*
X316043D03*
Y641159D03*
Y638600D03*
Y636041D03*
Y633482D03*
X285891Y704952D03*
Y707511D03*
Y710070D03*
Y712629D03*
Y715188D03*
X305377D03*
Y712629D03*
Y710070D03*
Y707511D03*
Y704952D03*
X800471Y494732D03*
Y497291D03*
Y499850D03*
Y502409D03*
Y504968D03*
X819957D03*
Y502409D03*
Y499850D03*
Y497291D03*
Y494732D03*
G54D47*
X134700Y694850D03*
G54D83*
X374768Y53823D03*
Y49223D03*
X374594Y84695D03*
Y80095D03*
G54D74*
X305906Y388386D03*
G54D56*
X159149Y687715D03*
X440100Y52457D03*
Y42657D03*
Y47557D03*
X635460Y521543D03*
X709000Y558300D03*
X826824Y42000D03*
X800824D03*
G54D57*
X197087Y679921D03*
G54D48*
X134700Y697350D03*
G54D75*
X305070Y522451D03*
Y525011D03*
X317870D03*
Y522451D03*
X305070Y527571D03*
Y530131D03*
X317870D03*
Y527571D03*
X313821Y556747D03*
Y559307D03*
Y561867D03*
Y564427D03*
Y566987D03*
Y569547D03*
Y572107D03*
Y574667D03*
Y577227D03*
Y579787D03*
X336021D03*
Y577227D03*
Y574667D03*
Y572107D03*
Y569547D03*
Y566987D03*
Y564427D03*
Y561867D03*
Y559307D03*
Y556747D03*
X355739Y575709D03*
Y573149D03*
Y570589D03*
Y568029D03*
Y565469D03*
Y562909D03*
Y560349D03*
Y557789D03*
Y555229D03*
Y552669D03*
Y550109D03*
Y547549D03*
X377939D03*
Y550109D03*
Y552669D03*
Y555229D03*
Y557789D03*
Y560349D03*
Y562909D03*
Y565469D03*
Y568029D03*
Y570589D03*
Y573149D03*
Y575709D03*
X374610Y695500D03*
Y692940D03*
Y690380D03*
Y687820D03*
Y685260D03*
Y682700D03*
Y680140D03*
Y677580D03*
Y675020D03*
Y672460D03*
X352410D03*
Y675020D03*
Y677580D03*
Y680140D03*
Y682700D03*
Y685260D03*
Y687820D03*
Y690380D03*
Y692940D03*
Y695500D03*
G54D84*
X372000Y68900D03*
G54D93*
X369969Y580758D03*
X507322Y22393D03*
X502622D03*
X582090Y48880D03*
X646377Y406737D03*
X642660Y562243D03*
X708000Y451700D03*
X675174Y459279D03*
X731076Y595829D03*
X782500Y415200D03*
X762400Y473100D03*
X885562Y307955D03*
X880223Y384817D03*
G54D39*
X65900Y671000D03*
X65700Y660900D03*
X70600Y665800D03*
X60700Y665900D03*
X70800Y660700D03*
X60800Y660900D03*
X70700Y671000D03*
X60600Y670900D03*
X65714Y665850D03*
X135019Y706095D03*
X130019D03*
X139916Y705822D03*
X130019Y724095D03*
X135019Y714845D03*
Y719095D03*
Y723595D03*
Y710595D03*
X130019Y720495D03*
Y716895D03*
Y713295D03*
Y709695D03*
X139916Y723822D03*
Y720222D03*
Y716622D03*
Y713022D03*
Y709422D03*
X306486Y643750D03*
X306286Y633650D03*
X311186Y638550D03*
X301286Y638650D03*
X311386Y633450D03*
X301386Y633650D03*
X311286Y643750D03*
X301186Y643650D03*
X306300Y638600D03*
X295634Y710070D03*
X290520Y715120D03*
X300620Y715220D03*
X290720Y705120D03*
X300720Y704920D03*
X290620Y710120D03*
X300520Y710020D03*
X295620Y705120D03*
X295820Y715220D03*
X371400Y606400D03*
X358900Y612800D03*
X358800Y606300D03*
X365300Y606500D03*
X371400Y612700D03*
X371300Y618800D03*
X365500Y619000D03*
X358900Y618800D03*
X365164Y612620D03*
X468000Y35400D03*
X464000Y35500D03*
X468000Y39500D03*
Y31500D03*
X472000Y35500D03*
X629200Y536040D03*
X629080Y539920D03*
X625500Y536100D03*
X625300Y539900D03*
X700546Y577599D03*
X691796D03*
X691296Y572599D03*
X705696D03*
X696296Y577599D03*
X709296Y572599D03*
Y577599D03*
X702096Y572599D03*
X694896D03*
X698496D03*
X704796Y577599D03*
X709569Y582496D03*
X698769D03*
X695169D03*
X691569D03*
X702369D03*
X705969D03*
X810200Y494900D03*
X815100Y499800D03*
X805200Y499900D03*
X815300Y494700D03*
X805300Y494900D03*
X815200Y505000D03*
X805100Y504900D03*
X810214Y499850D03*
X810400Y505000D03*
G54D66*
X230315Y679921D03*
G54D49*
X135019Y714845D03*
G54D67*
X258800Y669800D03*
X262400D03*
X662100Y429900D03*
X665700D03*
X662100Y409400D03*
X665700D03*
X662100Y413500D03*
X665700D03*
X662100Y417600D03*
X665700D03*
X662100Y421700D03*
X665700D03*
X662100Y425800D03*
X665700D03*
G54D76*
X320750Y592060D03*
Y589500D03*
Y586940D03*
X327250D03*
Y592060D03*
G54D94*
X369969Y586358D03*
X507322Y27993D03*
X502622D03*
X582090Y54480D03*
X646377Y412337D03*
X642660Y567843D03*
X708000Y457300D03*
X675174Y464879D03*
X731076Y601429D03*
X782500Y420800D03*
X762400Y478700D03*
X885562Y313555D03*
X880223Y390417D03*
G54D58*
X201801Y684252D03*
X225601D03*
G54D85*
X372000Y62500D03*
X344958Y107078D03*
G54D86*
X372000Y65500D03*
X344958Y110078D03*
G54D59*
X207795Y670886D03*
X203858D03*
X209764Y688956D03*
X205827D03*
X223544Y670886D03*
X219607D03*
X215670D03*
X211732D03*
X221575Y688956D03*
X217638D03*
X213701D03*
G54D95*
X369273Y645871D03*
X360049D03*
Y651827D03*
X369273D03*
G54D68*
X243199Y718747D03*
X232199D03*
X243199Y737947D03*
X232199D03*
X243199Y728347D03*
X232199D03*
X766680Y119860D03*
X755680D03*
G54D77*
X315252Y546325D03*
Y544355D03*
Y542385D03*
Y540415D03*
X306052D03*
Y542385D03*
Y544355D03*
Y546325D03*
X377739Y513804D03*
Y511839D03*
Y509869D03*
Y507899D03*
Y505934D03*
X361439D03*
Y507899D03*
Y509869D03*
Y511839D03*
Y513804D03*
G54D96*
X357290Y624270D03*
X373038D03*
Y600970D03*
X357290D03*
G54D69*
X274200Y663600D03*
X283200D03*
G54D87*
X374800Y111000D03*
Y116000D03*
Y121000D03*
X652500Y499600D03*
X651200Y545100D03*
X649900Y540300D03*
X713800Y619000D03*
X722100Y603700D03*
X772555Y39735D03*
X768300Y483800D03*
G54D78*
X327561Y656480D03*
X335311D03*
X331436Y663980D03*
X343006Y656555D03*
X350756D03*
X346881Y664055D03*
X555625Y68750D03*
X563375D03*
X559500Y76250D03*
X642345Y391494D03*
X650095D03*
X646220Y398994D03*
X783125Y66750D03*
X790875D03*
X786750Y93550D03*
X782875Y86050D03*
X790625D03*
X787000Y74250D03*
X785600Y117600D03*
X781725Y110100D03*
X789475D03*
X897344Y306791D03*
X893469Y299291D03*
X901219D03*
G54D79*
X299900Y657300D03*
Y660900D03*
G54D97*
X376814Y620494D03*
Y604746D03*
X353514D03*
Y620494D03*
G54D88*
X369200Y111000D03*
Y116000D03*
Y121000D03*
X646900Y499600D03*
X645600Y545100D03*
X644300Y540300D03*
X708200Y619000D03*
X716500Y603700D03*
X766955Y39735D03*
X762700Y483800D03*
G54D89*
X360500Y112960D03*
Y116700D03*
Y120440D03*
X351500D03*
Y112960D03*
X369500Y702460D03*
Y706200D03*
Y709940D03*
X360500D03*
Y702460D03*
G54D98*
X359258Y623920D03*
X361227D03*
X363195D03*
X365164D03*
X367133D03*
X369101D03*
X371070D03*
Y601320D03*
X369101D03*
X367133D03*
X365164D03*
X363195D03*
X361227D03*
X359258D03*
G54D99*
X376464Y618526D03*
Y616557D03*
Y614589D03*
Y612620D03*
Y610651D03*
Y608683D03*
Y606714D03*
X353864D03*
Y608683D03*
Y610651D03*
Y612620D03*
Y614589D03*
Y616557D03*
Y618526D03*
M02*
